(kicad_sch
	(version 20250114)
	(generator "eeschema")
	(generator_version "9.0")
	(paper "A3")
	(title_block
		(title "CM4 Baseboard")
		(date "2026-01-05")
		(rev "1.1.1")
		(company "Antmicro Ltd")
		(comment 1 "www.antmicro.com")
	)
	(bus_alias "GPIO"
		(members "0/SDA0" "1/SCL0" "2" "3" "4/TXD3" "5/RXD3" "6" "7" "8/TXD4" "9/RXD4"
			"10" "11" "12/RXD5" "13/TXD5" "14/RXD0" "15/TXD0" "16" "17" "18" "19"
			"20" "21" "22" "23" "24" "25" "26" "27" "AIN1" "AIN0"
		)
	)
	(text "Boot mode"
		(exclude_from_sim no)
		(at 91.44 257.81 0)
		(effects
			(font
				(size 2.54 2.54)
				(thickness 0.508)
				(bold yes)
			)
			(justify left bottom)
		)
	)
	(text "Misc."
		(exclude_from_sim no)
		(at 172.72 234.95 0)
		(effects
			(font
				(size 2.54 2.54)
				(bold yes)
			)
			(justify right bottom)
		)
	)
	(text "OUT: 600mA"
		(exclude_from_sim no)
		(at 46.99 146.05 0)
		(effects
			(font
				(size 1.27 1.27)
			)
			(justify left bottom)
		)
	)
	(text "DNP for CM4"
		(exclude_from_sim no)
		(at 193.04 102.87 0)
		(effects
			(font
				(size 1.27 1.27)
			)
			(justify left bottom)
		)
	)
	(text "Wakeup button"
		(exclude_from_sim no)
		(at 91.44 220.98 0)
		(effects
			(font
				(size 2.54 2.54)
				(thickness 0.508)
				(bold yes)
			)
			(justify left bottom)
		)
	)
	(text "OUT: 600mA"
		(exclude_from_sim no)
		(at 46.99 140.97 0)
		(effects
			(font
				(size 1.27 1.27)
			)
			(justify left bottom)
		)
	)
	(text "Raspberry CM4 connector"
		(exclude_from_sim no)
		(at 85.09 19.05 0)
		(effects
			(font
				(size 2.54 2.54)
				(bold yes)
			)
			(justify left bottom)
		)
	)
	(text "v-Mount for SDIO 1V8 Signalling"
		(exclude_from_sim no)
		(at 85.09 123.19 0)
		(effects
			(font
				(size 1.27 1.27)
			)
			(justify left bottom)
		)
	)
	(text "If CM is awake RUN_PG will be high \n  so the button doesn't do anything\nIf CM is asleep then RUN_PG will be \n  at 0v and so pull ~{RPi_RST} low"
		(exclude_from_sim no)
		(at 91.44 229.87 0)
		(effects
			(font
				(size 1.27 1.27)
			)
			(justify left bottom)
		)
	)
	(text "GPIO expander"
		(exclude_from_sim no)
		(at 242.57 26.67 0)
		(effects
			(font
				(size 2.54 2.54)
				(thickness 0.508)
				(bold yes)
			)
			(justify left bottom)
		)
	)
	(text "Additional 5V power \nfor Polarfire SOM"
		(exclude_from_sim no)
		(at 36.83 190.5 0)
		(effects
			(font
				(size 2.54 2.54)
				(thickness 0.508)
				(bold yes)
			)
			(justify left bottom)
		)
	)
	(text "<- GND on CM4; pull-up on PfSoM"
		(exclude_from_sim no)
		(at 91.44 87.63 0)
		(effects
			(font
				(size 1.27 1.27)
			)
			(justify left bottom)
		)
	)
	(text "Level conversion"
		(exclude_from_sim no)
		(at 266.7 114.3 0)
		(effects
			(font
				(size 2.54 2.54)
				(bold yes)
			)
			(justify right bottom)
		)
	)
	(text "Note:\nTo enable interrupt from SDIO.CD & FT4233\nset IOCON.MIRROR = 1"
		(exclude_from_sim no)
		(at 304.8 100.33 0)
		(effects
			(font
				(size 1.27 1.27)
			)
			(justify left bottom)
		)
	)
	(text "V_{BUS} connection\nfor Polarfire SOM"
		(exclude_from_sim no)
		(at 337.185 209.55 0)
		(effects
			(font
				(size 2.54 2.54)
				(thickness 0.508)
				(bold yes)
			)
			(justify left bottom)
		)
	)
	(text "DNP for CM4"
		(exclude_from_sim no)
		(at 137.16 86.36 0)
		(effects
			(font
				(size 1.27 1.27)
			)
			(justify left bottom)
		)
	)
	(text "CM mechanicals"
		(exclude_from_sim no)
		(at 331.47 125.73 0)
		(effects
			(font
				(size 2.54 2.54)
				(thickness 0.508)
				(bold yes)
			)
			(justify left bottom)
		)
	)
	(text "V_{BUS} on Polarfire ->"
		(exclude_from_sim no)
		(at 22.86 95.25 0)
		(effects
			(font
				(size 1.27 1.27)
			)
			(justify left bottom)
		)
	)
	(text "Note:\nI_{2}C address selection:\nA2|A1|A0| write address\n0 |0 |0 | 0x40\n0 |0 |1 | 0x42\n0 |1 |0 | 0x44\n0 |1 |1 | 0x46\n1 |0 |0 | 0x48\n1 |0 |1 | 0x4A\n1 |1 |0 | 0x4C\n1 |1 |1 | 0x4E"
		(exclude_from_sim no)
		(at 237.49 105.41 0)
		(effects
			(font
				(size 1.27 1.27)
			)
			(justify left bottom)
		)
	)
	(text "CM power indicators"
		(exclude_from_sim no)
		(at 163.195 185.42 0)
		(effects
			(font
				(size 2.54 2.54)
				(thickness 0.508)
				(bold yes)
			)
			(justify left bottom)
		)
	)
	(text "Reset button"
		(exclude_from_sim no)
		(at 91.44 185.42 0)
		(effects
			(font
				(size 2.54 2.54)
				(thickness 0.508)
				(bold yes)
			)
			(justify left bottom)
		)
	)
	(junction
		(at 60.96 140.97)
		(diameter 0)
		(color 0 0 0 0)
	)
	(junction
		(at 185.42 80.01)
		(diameter 0)
		(color 0 0 0 0)
	)
	(junction
		(at 168.91 133.35)
		(diameter 0)
		(color 0 0 0 0)
	)
	(junction
		(at 168.91 125.73)
		(diameter 0)
		(color 0 0 0 0)
	)
	(junction
		(at 134.62 223.52)
		(diameter 0)
		(color 0 0 0 0)
	)
	(junction
		(at 59.69 59.69)
		(diameter 0)
		(color 0 0 0 0)
	)
	(junction
		(at 255.27 63.5)
		(diameter 0)
		(color 0 0 0 0)
	)
	(junction
		(at 39.37 215.9)
		(diameter 0)
		(color 0 0 0 0)
	)
	(junction
		(at 134.62 201.93)
		(diameter 0)
		(color 0 0 0 0)
	)
	(junction
		(at 39.37 227.33)
		(diameter 0)
		(color 0 0 0 0)
	)
	(junction
		(at 134.62 199.39)
		(diameter 0)
		(color 0 0 0 0)
	)
	(junction
		(at 76.2 74.93)
		(diameter 0)
		(color 0 0 0 0)
	)
	(junction
		(at 59.69 125.73)
		(diameter 0)
		(color 0 0 0 0)
	)
	(junction
		(at 185.42 156.21)
		(diameter 0)
		(color 0 0 0 0)
	)
	(junction
		(at 59.69 72.39)
		(diameter 0)
		(color 0 0 0 0)
	)
	(junction
		(at 80.01 168.91)
		(diameter 0)
		(color 0 0 0 0)
	)
	(junction
		(at 41.91 24.13)
		(diameter 0)
		(color 0 0 0 0)
	)
	(junction
		(at 39.37 241.3)
		(diameter 0)
		(color 0 0 0 0)
	)
	(junction
		(at 168.91 215.9)
		(diameter 0)
		(color 0 0 0 0)
	)
	(junction
		(at 168.91 148.59)
		(diameter 0)
		(color 0 0 0 0)
	)
	(junction
		(at 248.92 212.09)
		(diameter 0)
		(color 0 0 0 0)
	)
	(junction
		(at 59.69 49.53)
		(diameter 0)
		(color 0 0 0 0)
	)
	(junction
		(at 130.81 269.24)
		(diameter 0)
		(color 0 0 0 0)
	)
	(junction
		(at 59.69 85.09)
		(diameter 0)
		(color 0 0 0 0)
	)
	(junction
		(at 30.48 198.12)
		(diameter 0)
		(color 0 0 0 0)
	)
	(junction
		(at 168.91 72.39)
		(diameter 0)
		(color 0 0 0 0)
	)
	(junction
		(at 68.58 232.41)
		(diameter 0)
		(color 0 0 0 0)
	)
	(junction
		(at 76.2 115.57)
		(diameter 0)
		(color 0 0 0 0)
	)
	(junction
		(at 59.69 97.79)
		(diameter 0)
		(color 0 0 0 0)
	)
	(junction
		(at 251.46 36.83)
		(diameter 0)
		(color 0 0 0 0)
	)
	(junction
		(at 59.69 115.57)
		(diameter 0)
		(color 0 0 0 0)
	)
	(junction
		(at 76.2 100.33)
		(diameter 0)
		(color 0 0 0 0)
	)
	(junction
		(at 41.91 146.05)
		(diameter 0)
		(color 0 0 0 0)
	)
	(junction
		(at 168.91 64.77)
		(diameter 0)
		(color 0 0 0 0)
	)
	(junction
		(at 68.58 209.55)
		(diameter 0)
		(color 0 0 0 0)
	)
	(junction
		(at 123.19 201.93)
		(diameter 0)
		(color 0 0 0 0)
	)
	(junction
		(at 76.2 49.53)
		(diameter 0)
		(color 0 0 0 0)
	)
	(junction
		(at 349.25 237.49)
		(diameter 0)
		(color 0 0 0 0)
	)
	(junction
		(at 135.89 24.13)
		(diameter 0)
		(color 0 0 0 0)
	)
	(junction
		(at 260.35 262.89)
		(diameter 0)
		(color 0 0 0 0)
	)
	(junction
		(at 185.42 118.11)
		(diameter 0)
		(color 0 0 0 0)
	)
	(junction
		(at 185.42 125.73)
		(diameter 0)
		(color 0 0 0 0)
	)
	(junction
		(at 59.69 41.91)
		(diameter 0)
		(color 0 0 0 0)
	)
	(junction
		(at 168.91 87.63)
		(diameter 0)
		(color 0 0 0 0)
	)
	(junction
		(at 168.91 156.21)
		(diameter 0)
		(color 0 0 0 0)
	)
	(junction
		(at 168.91 102.87)
		(diameter 0)
		(color 0 0 0 0)
	)
	(junction
		(at 68.58 198.12)
		(diameter 0)
		(color 0 0 0 0)
	)
	(junction
		(at 80.01 140.97)
		(diameter 0)
		(color 0 0 0 0)
	)
	(junction
		(at 76.2 123.19)
		(diameter 0)
		(color 0 0 0 0)
	)
	(junction
		(at 134.62 238.76)
		(diameter 0)
		(color 0 0 0 0)
	)
	(junction
		(at 168.91 57.15)
		(diameter 0)
		(color 0 0 0 0)
	)
	(junction
		(at 80.01 135.89)
		(diameter 0)
		(color 0 0 0 0)
	)
	(junction
		(at 80.01 133.35)
		(diameter 0)
		(color 0 0 0 0)
	)
	(junction
		(at 185.42 140.97)
		(diameter 0)
		(color 0 0 0 0)
	)
	(junction
		(at 190.5 270.51)
		(diameter 0)
		(color 0 0 0 0)
	)
	(junction
		(at 80.01 130.81)
		(diameter 0)
		(color 0 0 0 0)
	)
	(junction
		(at 350.52 218.44)
		(diameter 0)
		(color 0 0 0 0)
	)
	(junction
		(at 60.96 146.05)
		(diameter 0)
		(color 0 0 0 0)
	)
	(junction
		(at 185.42 72.39)
		(diameter 0)
		(color 0 0 0 0)
	)
	(junction
		(at 59.69 156.21)
		(diameter 0)
		(color 0 0 0 0)
	)
	(junction
		(at 35.56 251.46)
		(diameter 0)
		(color 0 0 0 0)
	)
	(junction
		(at 168.91 110.49)
		(diameter 0)
		(color 0 0 0 0)
	)
	(junction
		(at 30.48 220.98)
		(diameter 0)
		(color 0 0 0 0)
	)
	(junction
		(at 21.59 143.51)
		(diameter 0)
		(color 0 0 0 0)
	)
	(junction
		(at 358.14 227.33)
		(diameter 0)
		(color 0 0 0 0)
	)
	(junction
		(at 185.42 110.49)
		(diameter 0)
		(color 0 0 0 0)
	)
	(junction
		(at 185.42 64.77)
		(diameter 0)
		(color 0 0 0 0)
	)
	(junction
		(at 30.48 209.55)
		(diameter 0)
		(color 0 0 0 0)
	)
	(junction
		(at 68.58 220.98)
		(diameter 0)
		(color 0 0 0 0)
	)
	(junction
		(at 185.42 57.15)
		(diameter 0)
		(color 0 0 0 0)
	)
	(junction
		(at 80.01 156.21)
		(diameter 0)
		(color 0 0 0 0)
	)
	(junction
		(at 185.42 102.87)
		(diameter 0)
		(color 0 0 0 0)
	)
	(junction
		(at 59.69 107.95)
		(diameter 0)
		(color 0 0 0 0)
	)
	(junction
		(at 218.44 195.58)
		(diameter 0)
		(color 0 0 0 0)
	)
	(junction
		(at 44.45 241.3)
		(diameter 0)
		(color 0 0 0 0)
	)
	(junction
		(at 240.03 68.58)
		(diameter 0)
		(color 0 0 0 0)
	)
	(junction
		(at 247.65 66.04)
		(diameter 0)
		(color 0 0 0 0)
	)
	(junction
		(at 76.2 107.95)
		(diameter 0)
		(color 0 0 0 0)
	)
	(junction
		(at 123.19 238.76)
		(diameter 0)
		(color 0 0 0 0)
	)
	(junction
		(at 38.1 146.05)
		(diameter 0)
		(color 0 0 0 0)
	)
	(junction
		(at 168.91 49.53)
		(diameter 0)
		(color 0 0 0 0)
	)
	(junction
		(at 30.48 232.41)
		(diameter 0)
		(color 0 0 0 0)
	)
	(junction
		(at 168.91 140.97)
		(diameter 0)
		(color 0 0 0 0)
	)
	(junction
		(at 134.62 186.69)
		(diameter 0)
		(color 0 0 0 0)
	)
	(junction
		(at 185.42 133.35)
		(diameter 0)
		(color 0 0 0 0)
	)
	(junction
		(at 168.91 80.01)
		(diameter 0)
		(color 0 0 0 0)
	)
	(junction
		(at 185.42 148.59)
		(diameter 0)
		(color 0 0 0 0)
	)
	(junction
		(at 76.2 62.23)
		(diameter 0)
		(color 0 0 0 0)
	)
	(junction
		(at 189.23 215.9)
		(diameter 0)
		(color 0 0 0 0)
	)
	(junction
		(at 76.2 41.91)
		(diameter 0)
		(color 0 0 0 0)
	)
	(junction
		(at 134.62 236.22)
		(diameter 0)
		(color 0 0 0 0)
	)
	(junction
		(at 168.91 95.25)
		(diameter 0)
		(color 0 0 0 0)
	)
	(junction
		(at 185.42 49.53)
		(diameter 0)
		(color 0 0 0 0)
	)
	(junction
		(at 275.59 76.2)
		(diameter 0)
		(color 0 0 0 0)
	)
	(junction
		(at 80.01 138.43)
		(diameter 0)
		(color 0 0 0 0)
	)
	(junction
		(at 248.92 147.32)
		(diameter 0)
		(color 0 0 0 0)
	)
	(junction
		(at 25.4 143.51)
		(diameter 0)
		(color 0 0 0 0)
	)
	(junction
		(at 306.07 43.18)
		(diameter 0)
		(color 0 0 0 0)
	)
	(junction
		(at 168.91 118.11)
		(diameter 0)
		(color 0 0 0 0)
	)
	(junction
		(at 139.7 278.13)
		(diameter 0)
		(color 0 0 0 0)
	)
	(no_connect
		(at 74.93 128.27)
	)
	(no_connect
		(at 74.93 57.15)
	)
	(no_connect
		(at 170.18 36.83)
	)
	(no_connect
		(at 60.96 123.19)
	)
	(no_connect
		(at 196.85 123.19)
	)
	(no_connect
		(at 60.96 113.03)
	)
	(no_connect
		(at 60.96 120.65)
	)
	(no_connect
		(at 278.13 53.34)
	)
	(no_connect
		(at 60.96 118.11)
	)
	(no_connect
		(at 107.95 271.78)
	)
	(no_connect
		(at 170.18 39.37)
	)
	(no_connect
		(at 196.85 120.65)
	)
	(bus_entry
		(at 283.21 165.1)
		(size -2.54 2.54)
		(stroke
			(width 0)
			(type default)
		)
	)
	(bus_entry
		(at 200.66 140.97)
		(size -2.54 2.54)
		(stroke
			(width 0)
			(type default)
		)
	)
	(bus_entry
		(at 97.79 49.53)
		(size -2.54 2.54)
		(stroke
			(width 0)
			(type default)
		)
	)
	(bus_entry
		(at 393.7 68.58)
		(size -2.54 2.54)
		(stroke
			(width 0)
			(type default)
		)
	)
	(bus_entry
		(at 135.89 57.15)
		(size 2.54 2.54)
		(stroke
			(width 0)
			(type default)
		)
	)
	(bus_entry
		(at 135.89 90.17)
		(size 2.54 2.54)
		(stroke
			(width 0)
			(type default)
		)
	)
	(bus_entry
		(at 152.4 72.39)
		(size 2.54 2.54)
		(stroke
			(width 0)
			(type default)
		)
	)
	(bus_entry
		(at 393.7 33.02)
		(size -2.54 2.54)
		(stroke
			(width 0)
			(type default)
		)
	)
	(bus_entry
		(at 154.94 153.67)
		(size 2.54 -2.54)
		(stroke
			(width 0)
			(type default)
		)
	)
	(bus_entry
		(at 41.91 36.83)
		(size 2.54 2.54)
		(stroke
			(width 0)
			(type default)
		)
	)
	(bus_entry
		(at 283.21 229.87)
		(size -2.54 2.54)
		(stroke
			(width 0)
			(type default)
		)
	)
	(bus_entry
		(at 200.66 133.35)
		(size -2.54 2.54)
		(stroke
			(width 0)
			(type default)
		)
	)
	(bus_entry
		(at 135.89 151.13)
		(size 2.54 2.54)
		(stroke
			(width 0)
			(type default)
		)
	)
	(bus_entry
		(at 152.4 82.55)
		(size 2.54 2.54)
		(stroke
			(width 0)
			(type default)
		)
	)
	(bus_entry
		(at 393.7 71.12)
		(size -2.54 2.54)
		(stroke
			(width 0)
			(type default)
		)
	)
	(bus_entry
		(at 93.98 107.95)
		(size -2.54 2.54)
		(stroke
			(width 0)
			(type default)
		)
	)
	(bus_entry
		(at 200.66 90.17)
		(size -2.54 2.54)
		(stroke
			(width 0)
			(type default)
		)
	)
	(bus_entry
		(at 72.39 218.44)
		(size -2.54 2.54)
		(stroke
			(width 0)
			(type default)
		)
	)
	(bus_entry
		(at 135.89 52.07)
		(size 2.54 2.54)
		(stroke
			(width 0)
			(type default)
		)
	)
	(bus_entry
		(at 393.7 30.48)
		(size -2.54 2.54)
		(stroke
			(width 0)
			(type default)
		)
	)
	(bus_entry
		(at 72.39 207.01)
		(size -2.54 2.54)
		(stroke
			(width 0)
			(type default)
		)
	)
	(bus_entry
		(at 200.66 49.53)
		(size -2.54 2.54)
		(stroke
			(width 0)
			(type default)
		)
	)
	(bus_entry
		(at 135.89 87.63)
		(size 2.54 2.54)
		(stroke
			(width 0)
			(type default)
		)
	)
	(bus_entry
		(at 393.7 88.9)
		(size -2.54 2.54)
		(stroke
			(width 0)
			(type default)
		)
	)
	(bus_entry
		(at 200.66 36.83)
		(size -2.54 2.54)
		(stroke
			(width 0)
			(type default)
		)
	)
	(bus_entry
		(at 393.7 35.56)
		(size -2.54 2.54)
		(stroke
			(width 0)
			(type default)
		)
	)
	(bus_entry
		(at 97.79 41.91)
		(size -2.54 2.54)
		(stroke
			(width 0)
			(type default)
		)
	)
	(bus_entry
		(at 200.66 85.09)
		(size -2.54 2.54)
		(stroke
			(width 0)
			(type default)
		)
	)
	(bus_entry
		(at 331.47 48.26)
		(size -2.54 2.54)
		(stroke
			(width 0)
			(type default)
		)
	)
	(bus_entry
		(at 393.7 76.2)
		(size -2.54 2.54)
		(stroke
			(width 0)
			(type default)
		)
	)
	(bus_entry
		(at 72.39 195.58)
		(size -2.54 2.54)
		(stroke
			(width 0)
			(type default)
		)
	)
	(bus_entry
		(at 219.71 105.41)
		(size -2.54 2.54)
		(stroke
			(width 0)
			(type default)
		)
	)
	(bus_entry
		(at 200.66 52.07)
		(size -2.54 2.54)
		(stroke
			(width 0)
			(type default)
		)
	)
	(bus_entry
		(at 331.47 58.42)
		(size -2.54 2.54)
		(stroke
			(width 0)
			(type default)
		)
	)
	(bus_entry
		(at 200.66 34.29)
		(size -2.54 2.54)
		(stroke
			(width 0)
			(type default)
		)
	)
	(bus_entry
		(at 39.37 130.81)
		(size 2.54 2.54)
		(stroke
			(width 0)
			(type default)
		)
	)
	(bus_entry
		(at 219.71 110.49)
		(size -2.54 2.54)
		(stroke
			(width 0)
			(type default)
		)
	)
	(bus_entry
		(at 393.7 81.28)
		(size -2.54 2.54)
		(stroke
			(width 0)
			(type default)
		)
	)
	(bus_entry
		(at 200.66 85.09)
		(size -2.54 2.54)
		(stroke
			(width 0)
			(type default)
		)
	)
	(bus_entry
		(at 214.63 252.73)
		(size -2.54 2.54)
		(stroke
			(width 0)
			(type default)
		)
	)
	(bus_entry
		(at 331.47 55.88)
		(size -2.54 2.54)
		(stroke
			(width 0)
			(type default)
		)
	)
	(bus_entry
		(at 393.7 45.72)
		(size -2.54 2.54)
		(stroke
			(width 0)
			(type default)
		)
	)
	(bus_entry
		(at 200.66 125.73)
		(size -2.54 2.54)
		(stroke
			(width 0)
			(type default)
		)
	)
	(bus_entry
		(at 283.21 160.02)
		(size -2.54 2.54)
		(stroke
			(width 0)
			(type default)
		)
	)
	(bus_entry
		(at 39.37 133.35)
		(size 2.54 2.54)
		(stroke
			(width 0)
			(type default)
		)
	)
	(bus_entry
		(at 97.79 36.83)
		(size -2.54 2.54)
		(stroke
			(width 0)
			(type default)
		)
	)
	(bus_entry
		(at 135.89 95.25)
		(size 2.54 2.54)
		(stroke
			(width 0)
			(type default)
		)
	)
	(bus_entry
		(at 266.7 40.64)
		(size 2.54 2.54)
		(stroke
			(width 0)
			(type default)
		)
	)
	(bus_entry
		(at 393.7 63.5)
		(size -2.54 2.54)
		(stroke
			(width 0)
			(type default)
		)
	)
	(bus_entry
		(at 152.4 80.01)
		(size 2.54 2.54)
		(stroke
			(width 0)
			(type default)
		)
	)
	(bus_entry
		(at 135.89 125.73)
		(size 2.54 2.54)
		(stroke
			(width 0)
			(type default)
		)
	)
	(bus_entry
		(at 135.89 102.87)
		(size 2.54 2.54)
		(stroke
			(width 0)
			(type default)
		)
	)
	(bus_entry
		(at 135.89 148.59)
		(size 2.54 2.54)
		(stroke
			(width 0)
			(type default)
		)
	)
	(bus_entry
		(at 266.7 38.1)
		(size 2.54 2.54)
		(stroke
			(width 0)
			(type default)
		)
	)
	(bus_entry
		(at 97.79 44.45)
		(size -2.54 2.54)
		(stroke
			(width 0)
			(type default)
		)
	)
	(bus_entry
		(at 200.66 151.13)
		(size -2.54 2.54)
		(stroke
			(width 0)
			(type default)
		)
	)
	(bus_entry
		(at 393.7 43.18)
		(size -2.54 2.54)
		(stroke
			(width 0)
			(type default)
		)
	)
	(bus_entry
		(at 331.47 38.1)
		(size -2.54 2.54)
		(stroke
			(width 0)
			(type default)
		)
	)
	(bus_entry
		(at 200.66 67.31)
		(size -2.54 2.54)
		(stroke
			(width 0)
			(type default)
		)
	)
	(bus_entry
		(at 41.91 34.29)
		(size 2.54 2.54)
		(stroke
			(width 0)
			(type default)
		)
	)
	(bus_entry
		(at 135.89 128.27)
		(size 2.54 2.54)
		(stroke
			(width 0)
			(type default)
		)
	)
	(bus_entry
		(at 72.39 229.87)
		(size -2.54 2.54)
		(stroke
			(width 0)
			(type default)
		)
	)
	(bus_entry
		(at 393.7 55.88)
		(size -2.54 2.54)
		(stroke
			(width 0)
			(type default)
		)
	)
	(bus_entry
		(at 135.89 118.11)
		(size 2.54 2.54)
		(stroke
			(width 0)
			(type default)
		)
	)
	(bus_entry
		(at 266.7 40.64)
		(size 2.54 2.54)
		(stroke
			(width 0)
			(type default)
		)
	)
	(bus_entry
		(at 393.7 50.8)
		(size -2.54 2.54)
		(stroke
			(width 0)
			(type default)
		)
	)
	(bus_entry
		(at 72.39 195.58)
		(size -2.54 2.54)
		(stroke
			(width 0)
			(type default)
		)
	)
	(bus_entry
		(at 41.91 44.45)
		(size 2.54 2.54)
		(stroke
			(width 0)
			(type default)
		)
	)
	(bus_entry
		(at 200.66 135.89)
		(size -2.54 2.54)
		(stroke
			(width 0)
			(type default)
		)
	)
	(bus_entry
		(at 283.21 219.71)
		(size -2.54 2.54)
		(stroke
			(width 0)
			(type default)
		)
	)
	(bus_entry
		(at 393.7 40.64)
		(size -2.54 2.54)
		(stroke
			(width 0)
			(type default)
		)
	)
	(bus_entry
		(at 393.7 27.94)
		(size -2.54 2.54)
		(stroke
			(width 0)
			(type default)
		)
	)
	(bus_entry
		(at 200.66 82.55)
		(size -2.54 2.54)
		(stroke
			(width 0)
			(type default)
		)
	)
	(bus_entry
		(at 393.7 25.4)
		(size -2.54 2.54)
		(stroke
			(width 0)
			(type default)
		)
	)
	(bus_entry
		(at 200.66 92.71)
		(size -2.54 2.54)
		(stroke
			(width 0)
			(type default)
		)
	)
	(bus_entry
		(at 283.21 224.79)
		(size -2.54 2.54)
		(stroke
			(width 0)
			(type default)
		)
	)
	(bus_entry
		(at 200.66 87.63)
		(size -2.54 2.54)
		(stroke
			(width 0)
			(type default)
		)
	)
	(bus_entry
		(at 266.7 38.1)
		(size 2.54 2.54)
		(stroke
			(width 0)
			(type default)
		)
	)
	(bus_entry
		(at 393.7 58.42)
		(size -2.54 2.54)
		(stroke
			(width 0)
			(type default)
		)
	)
	(bus_entry
		(at 104.14 168.91)
		(size -2.54 2.54)
		(stroke
			(width 0)
			(type default)
		)
	)
	(bus_entry
		(at 393.7 93.98)
		(size -2.54 2.54)
		(stroke
			(width 0)
			(type default)
		)
	)
	(bus_entry
		(at 93.98 102.87)
		(size -2.54 2.54)
		(stroke
			(width 0)
			(type default)
		)
	)
	(bus_entry
		(at 200.66 59.69)
		(size -2.54 2.54)
		(stroke
			(width 0)
			(type default)
		)
	)
	(bus_entry
		(at 200.66 57.15)
		(size -2.54 2.54)
		(stroke
			(width 0)
			(type default)
		)
	)
	(bus_entry
		(at 39.37 125.73)
		(size 2.54 2.54)
		(stroke
			(width 0)
			(type default)
		)
	)
	(bus_entry
		(at 219.71 102.87)
		(size -2.54 2.54)
		(stroke
			(width 0)
			(type default)
		)
	)
	(bus_entry
		(at 393.7 38.1)
		(size -2.54 2.54)
		(stroke
			(width 0)
			(type default)
		)
	)
	(bus_entry
		(at 200.66 74.93)
		(size -2.54 2.54)
		(stroke
			(width 0)
			(type default)
		)
	)
	(bus_entry
		(at 135.89 97.79)
		(size 2.54 2.54)
		(stroke
			(width 0)
			(type default)
		)
	)
	(bus_entry
		(at 219.71 41.91)
		(size -2.54 2.54)
		(stroke
			(width 0)
			(type default)
		)
	)
	(bus_entry
		(at 200.66 148.59)
		(size -2.54 2.54)
		(stroke
			(width 0)
			(type default)
		)
	)
	(bus_entry
		(at 393.7 73.66)
		(size -2.54 2.54)
		(stroke
			(width 0)
			(type default)
		)
	)
	(bus_entry
		(at 393.7 83.82)
		(size -2.54 2.54)
		(stroke
			(width 0)
			(type default)
		)
	)
	(bus_entry
		(at 93.98 115.57)
		(size -2.54 2.54)
		(stroke
			(width 0)
			(type default)
		)
	)
	(bus_entry
		(at 135.89 135.89)
		(size 2.54 2.54)
		(stroke
			(width 0)
			(type default)
		)
	)
	(bus_entry
		(at 135.89 120.65)
		(size 2.54 2.54)
		(stroke
			(width 0)
			(type default)
		)
	)
	(bus_entry
		(at 200.66 72.39)
		(size -2.54 2.54)
		(stroke
			(width 0)
			(type default)
		)
	)
	(bus_entry
		(at 331.47 50.8)
		(size -2.54 2.54)
		(stroke
			(width 0)
			(type default)
		)
	)
	(bus_entry
		(at 93.98 110.49)
		(size -2.54 2.54)
		(stroke
			(width 0)
			(type default)
		)
	)
	(bus_entry
		(at 135.89 41.91)
		(size 2.54 2.54)
		(stroke
			(width 0)
			(type default)
		)
	)
	(bus_entry
		(at 200.66 90.17)
		(size -2.54 2.54)
		(stroke
			(width 0)
			(type default)
		)
	)
	(bus_entry
		(at 135.89 59.69)
		(size 2.54 2.54)
		(stroke
			(width 0)
			(type default)
		)
	)
	(bus_entry
		(at 393.7 53.34)
		(size -2.54 2.54)
		(stroke
			(width 0)
			(type default)
		)
	)
	(bus_entry
		(at 41.91 41.91)
		(size 2.54 2.54)
		(stroke
			(width 0)
			(type default)
		)
	)
	(bus_entry
		(at 135.89 44.45)
		(size 2.54 2.54)
		(stroke
			(width 0)
			(type default)
		)
	)
	(bus_entry
		(at 152.4 64.77)
		(size 2.54 2.54)
		(stroke
			(width 0)
			(type default)
		)
	)
	(bus_entry
		(at 104.14 166.37)
		(size -2.54 2.54)
		(stroke
			(width 0)
			(type default)
		)
	)
	(bus_entry
		(at 200.66 128.27)
		(size -2.54 2.54)
		(stroke
			(width 0)
			(type default)
		)
	)
	(bus_entry
		(at 283.21 214.63)
		(size -2.54 2.54)
		(stroke
			(width 0)
			(type default)
		)
	)
	(bus_entry
		(at 219.71 113.03)
		(size -2.54 2.54)
		(stroke
			(width 0)
			(type default)
		)
	)
	(bus_entry
		(at 135.89 156.21)
		(size 2.54 2.54)
		(stroke
			(width 0)
			(type default)
		)
	)
	(bus_entry
		(at 200.66 31.75)
		(size -2.54 2.54)
		(stroke
			(width 0)
			(type default)
		)
	)
	(bus_entry
		(at 393.7 60.96)
		(size -2.54 2.54)
		(stroke
			(width 0)
			(type default)
		)
	)
	(bus_entry
		(at 200.66 87.63)
		(size -2.54 2.54)
		(stroke
			(width 0)
			(type default)
		)
	)
	(bus_entry
		(at 331.47 63.5)
		(size -2.54 2.54)
		(stroke
			(width 0)
			(type default)
		)
	)
	(bus_entry
		(at 72.39 218.44)
		(size -2.54 2.54)
		(stroke
			(width 0)
			(type default)
		)
	)
	(bus_entry
		(at 97.79 52.07)
		(size -2.54 2.54)
		(stroke
			(width 0)
			(type default)
		)
	)
	(bus_entry
		(at 393.7 22.86)
		(size -2.54 2.54)
		(stroke
			(width 0)
			(type default)
		)
	)
	(bus_entry
		(at 331.47 66.04)
		(size -2.54 2.54)
		(stroke
			(width 0)
			(type default)
		)
	)
	(bus_entry
		(at 331.47 33.02)
		(size -2.54 2.54)
		(stroke
			(width 0)
			(type default)
		)
	)
	(bus_entry
		(at 152.4 67.31)
		(size 2.54 2.54)
		(stroke
			(width 0)
			(type default)
		)
	)
	(bus_entry
		(at 331.47 60.96)
		(size -2.54 2.54)
		(stroke
			(width 0)
			(type default)
		)
	)
	(bus_entry
		(at 331.47 40.64)
		(size -2.54 2.54)
		(stroke
			(width 0)
			(type default)
		)
	)
	(bus_entry
		(at 72.39 207.01)
		(size -2.54 2.54)
		(stroke
			(width 0)
			(type default)
		)
	)
	(bus_entry
		(at 200.66 92.71)
		(size -2.54 2.54)
		(stroke
			(width 0)
			(type default)
		)
	)
	(bus_entry
		(at 193.04 238.76)
		(size 2.54 2.54)
		(stroke
			(width 0)
			(type default)
		)
	)
	(bus_entry
		(at 39.37 107.95)
		(size 2.54 2.54)
		(stroke
			(width 0)
			(type default)
		)
	)
	(bus_entry
		(at 393.7 66.04)
		(size -2.54 2.54)
		(stroke
			(width 0)
			(type default)
		)
	)
	(bus_entry
		(at 72.39 229.87)
		(size -2.54 2.54)
		(stroke
			(width 0)
			(type default)
		)
	)
	(bus_entry
		(at 154.94 156.21)
		(size 2.54 -2.54)
		(stroke
			(width 0)
			(type default)
		)
	)
	(bus_entry
		(at 393.7 78.74)
		(size -2.54 2.54)
		(stroke
			(width 0)
			(type default)
		)
	)
	(bus_entry
		(at 331.47 45.72)
		(size -2.54 2.54)
		(stroke
			(width 0)
			(type default)
		)
	)
	(bus_entry
		(at 393.7 86.36)
		(size -2.54 2.54)
		(stroke
			(width 0)
			(type default)
		)
	)
	(bus_entry
		(at 135.89 49.53)
		(size 2.54 2.54)
		(stroke
			(width 0)
			(type default)
		)
	)
	(bus_entry
		(at 135.89 153.67)
		(size 2.54 2.54)
		(stroke
			(width 0)
			(type default)
		)
	)
	(bus_entry
		(at 135.89 133.35)
		(size 2.54 2.54)
		(stroke
			(width 0)
			(type default)
		)
	)
	(bus_entry
		(at 135.89 105.41)
		(size 2.54 2.54)
		(stroke
			(width 0)
			(type default)
		)
	)
	(bus_entry
		(at 200.66 143.51)
		(size -2.54 2.54)
		(stroke
			(width 0)
			(type default)
		)
	)
	(bus_entry
		(at 97.79 34.29)
		(size -2.54 2.54)
		(stroke
			(width 0)
			(type default)
		)
	)
	(bus_entry
		(at 393.7 20.32)
		(size -2.54 2.54)
		(stroke
			(width 0)
			(type default)
		)
	)
	(bus_entry
		(at 283.21 149.86)
		(size -2.54 2.54)
		(stroke
			(width 0)
			(type default)
		)
	)
	(bus_entry
		(at 214.63 250.19)
		(size -2.54 2.54)
		(stroke
			(width 0)
			(type default)
		)
	)
	(bus_entry
		(at 135.89 140.97)
		(size 2.54 2.54)
		(stroke
			(width 0)
			(type default)
		)
	)
	(bus_entry
		(at 331.47 35.56)
		(size -2.54 2.54)
		(stroke
			(width 0)
			(type default)
		)
	)
	(bus_entry
		(at 135.89 143.51)
		(size 2.54 2.54)
		(stroke
			(width 0)
			(type default)
		)
	)
	(bus_entry
		(at 200.66 80.01)
		(size -2.54 2.54)
		(stroke
			(width 0)
			(type default)
		)
	)
	(bus_entry
		(at 135.89 31.75)
		(size 2.54 2.54)
		(stroke
			(width 0)
			(type default)
		)
	)
	(bus_entry
		(at 393.7 48.26)
		(size -2.54 2.54)
		(stroke
			(width 0)
			(type default)
		)
	)
	(bus_entry
		(at 283.21 154.94)
		(size -2.54 2.54)
		(stroke
			(width 0)
			(type default)
		)
	)
	(bus_entry
		(at 331.47 43.18)
		(size -2.54 2.54)
		(stroke
			(width 0)
			(type default)
		)
	)
	(bus_entry
		(at 152.4 74.93)
		(size 2.54 2.54)
		(stroke
			(width 0)
			(type default)
		)
	)
	(bus_entry
		(at 93.98 118.11)
		(size -2.54 2.54)
		(stroke
			(width 0)
			(type default)
		)
	)
	(bus_entry
		(at 135.89 113.03)
		(size 2.54 2.54)
		(stroke
			(width 0)
			(type default)
		)
	)
	(bus_entry
		(at 200.66 64.77)
		(size -2.54 2.54)
		(stroke
			(width 0)
			(type default)
		)
	)
	(bus_entry
		(at 135.89 110.49)
		(size 2.54 2.54)
		(stroke
			(width 0)
			(type default)
		)
	)
	(bus_entry
		(at 393.7 91.44)
		(size -2.54 2.54)
		(stroke
			(width 0)
			(type default)
		)
	)
	(wire
		(pts
			(xy 271.78 172.72) (xy 271.78 175.26)
		)
		(stroke
			(width 0)
			(type default)
		)
	)
	(wire
		(pts
			(xy 134.62 201.93) (xy 134.62 203.2)
		)
		(stroke
			(width 0)
			(type default)
		)
	)
	(wire
		(pts
			(xy 97.79 59.69) (xy 100.33 59.69)
		)
		(stroke
			(width 0)
			(type default)
		)
	)
	(wire
		(pts
			(xy 344.17 237.49) (xy 349.25 237.49)
		)
		(stroke
			(width 0)
			(type default)
		)
	)
	(bus
		(pts
			(xy 393.7 73.66) (xy 393.7 76.2)
		)
		(stroke
			(width 0)
			(type default)
		)
	)
	(wire
		(pts
			(xy 184.15 72.39) (xy 185.42 72.39)
		)
		(stroke
			(width 0)
			(type default)
		)
	)
	(wire
		(pts
			(xy 255.27 63.5) (xy 278.13 63.5)
		)
		(stroke
			(width 0)
			(type default)
		)
	)
	(bus
		(pts
			(xy 219.71 110.49) (xy 219.71 113.03)
		)
		(stroke
			(width 0)
			(type default)
		)
	)
	(wire
		(pts
			(xy 80.01 130.81) (xy 80.01 133.35)
		)
		(stroke
			(width 0)
			(type default)
		)
	)
	(wire
		(pts
			(xy 41.91 133.35) (xy 60.96 133.35)
		)
		(stroke
			(width 0)
			(type default)
		)
	)
	(bus
		(pts
			(xy 151.13 64.77) (xy 152.4 64.77)
		)
		(stroke
			(width 0)
			(type default)
		)
	)
	(wire
		(pts
			(xy 168.91 125.73) (xy 168.91 133.35)
		)
		(stroke
			(width 0)
			(type default)
		)
	)
	(wire
		(pts
			(xy 52.07 232.41) (xy 68.58 232.41)
		)
		(stroke
			(width 0)
			(type default)
		)
	)
	(wire
		(pts
			(xy 377.19 27.94) (xy 391.16 27.94)
		)
		(stroke
			(width 0)
			(type default)
		)
	)
	(wire
		(pts
			(xy 80.01 130.81) (xy 74.93 130.81)
		)
		(stroke
			(width 0)
			(type default)
		)
	)
	(wire
		(pts
			(xy 340.36 143.51) (xy 340.36 142.24)
		)
		(stroke
			(width 0)
			(type default)
		)
	)
	(wire
		(pts
			(xy 130.81 278.13) (xy 139.7 278.13)
		)
		(stroke
			(width 0)
			(type default)
		)
	)
	(wire
		(pts
			(xy 44.45 77.47) (xy 60.96 77.47)
		)
		(stroke
			(width 0)
			(type default)
		)
	)
	(bus
		(pts
			(xy 214.63 250.19) (xy 214.63 252.73)
		)
		(stroke
			(width 0)
			(type default)
		)
	)
	(wire
		(pts
			(xy 377.19 96.52) (xy 391.16 96.52)
		)
		(stroke
			(width 0)
			(type default)
		)
	)
	(bus
		(pts
			(xy 219.71 102.87) (xy 219.71 105.41)
		)
		(stroke
			(width 0)
			(type default)
		)
	)
	(wire
		(pts
			(xy 134.62 238.76) (xy 134.62 240.03)
		)
		(stroke
			(width 0)
			(type default)
		)
	)
	(wire
		(pts
			(xy 138.43 143.51) (xy 170.18 143.51)
		)
		(stroke
			(width 0)
			(type default)
		)
	)
	(wire
		(pts
			(xy 255.27 63.5) (xy 255.27 69.85)
		)
		(stroke
			(width 0)
			(type default)
		)
	)
	(wire
		(pts
			(xy 340.36 151.13) (xy 341.63 151.13)
		)
		(stroke
			(width 0)
			(type default)
		)
	)
	(wire
		(pts
			(xy 60.96 107.95) (xy 59.69 107.95)
		)
		(stroke
			(width 0)
			(type default)
		)
	)
	(bus
		(pts
			(xy 200.66 57.15) (xy 200.66 59.69)
		)
		(stroke
			(width 0)
			(type default)
		)
	)
	(wire
		(pts
			(xy 184.15 148.59) (xy 185.42 148.59)
		)
		(stroke
			(width 0)
			(type default)
		)
	)
	(wire
		(pts
			(xy 91.44 72.39) (xy 74.93 72.39)
		)
		(stroke
			(width 0)
			(type default)
		)
	)
	(wire
		(pts
			(xy 114.3 238.76) (xy 114.3 240.03)
		)
		(stroke
			(width 0)
			(type default)
		)
	)
	(bus
		(pts
			(xy 135.89 97.79) (xy 135.89 102.87)
		)
		(stroke
			(width 0)
			(type default)
		)
	)
	(bus
		(pts
			(xy 135.89 105.41) (xy 135.89 110.49)
		)
		(stroke
			(width 0)
			(type default)
		)
	)
	(wire
		(pts
			(xy 132.08 186.69) (xy 132.08 187.96)
		)
		(stroke
			(width 0)
			(type default)
		)
	)
	(wire
		(pts
			(xy 184.15 44.45) (xy 217.17 44.45)
		)
		(stroke
			(width 0)
			(type default)
		)
	)
	(wire
		(pts
			(xy 154.94 69.85) (xy 170.18 69.85)
		)
		(stroke
			(width 0)
			(type default)
		)
	)
	(wire
		(pts
			(xy 60.96 95.25) (xy 44.45 95.25)
		)
		(stroke
			(width 0)
			(type default)
		)
	)
	(wire
		(pts
			(xy 280.67 152.4) (xy 270.51 152.4)
		)
		(stroke
			(width 0)
			(type default)
		)
	)
	(bus
		(pts
			(xy 93.98 115.57) (xy 93.98 118.11)
		)
		(stroke
			(width 0)
			(type default)
		)
	)
	(wire
		(pts
			(xy 127 269.24) (xy 130.81 269.24)
		)
		(stroke
			(width 0)
			(type default)
		)
	)
	(bus
		(pts
			(xy 133.35 118.11) (xy 135.89 118.11)
		)
		(stroke
			(width 0)
			(type default)
		)
	)
	(wire
		(pts
			(xy 123.19 238.76) (xy 134.62 238.76)
		)
		(stroke
			(width 0)
			(type default)
		)
	)
	(bus
		(pts
			(xy 135.89 128.27) (xy 135.89 133.35)
		)
		(stroke
			(width 0)
			(type default)
		)
	)
	(wire
		(pts
			(xy 280.67 217.17) (xy 270.51 217.17)
		)
		(stroke
			(width 0)
			(type default)
		)
	)
	(wire
		(pts
			(xy 59.69 125.73) (xy 59.69 156.21)
		)
		(stroke
			(width 0)
			(type default)
		)
	)
	(bus
		(pts
			(xy 200.66 87.63) (xy 200.66 90.17)
		)
		(stroke
			(width 0)
			(type default)
		)
	)
	(wire
		(pts
			(xy 275.59 35.56) (xy 275.59 33.02)
		)
		(stroke
			(width 0)
			(type default)
		)
	)
	(wire
		(pts
			(xy 60.96 62.23) (xy 44.45 62.23)
		)
		(stroke
			(width 0)
			(type default)
		)
	)
	(wire
		(pts
			(xy 303.53 53.34) (xy 328.93 53.34)
		)
		(stroke
			(width 0)
			(type default)
		)
	)
	(wire
		(pts
			(xy 31.75 140.97) (xy 60.96 140.97)
		)
		(stroke
			(width 0)
			(type default)
		)
	)
	(wire
		(pts
			(xy 303.53 60.96) (xy 328.93 60.96)
		)
		(stroke
			(width 0)
			(type default)
		)
	)
	(wire
		(pts
			(xy 60.96 87.63) (xy 44.45 87.63)
		)
		(stroke
			(width 0)
			(type default)
		)
	)
	(wire
		(pts
			(xy 35.56 259.08) (xy 35.56 257.81)
		)
		(stroke
			(width 0)
			(type default)
		)
	)
	(wire
		(pts
			(xy 184.15 130.81) (xy 198.12 130.81)
		)
		(stroke
			(width 0)
			(type default)
		)
	)
	(wire
		(pts
			(xy 349.25 218.44) (xy 350.52 218.44)
		)
		(stroke
			(width 0)
			(type default)
		)
	)
	(wire
		(pts
			(xy 358.14 240.03) (xy 358.14 245.11)
		)
		(stroke
			(width 0)
			(type default)
		)
	)
	(bus
		(pts
			(xy 200.66 171.45) (xy 154.94 171.45)
		)
		(stroke
			(width 0)
			(type default)
		)
	)
	(bus
		(pts
			(xy 201.93 30.48) (xy 200.66 30.48)
		)
		(stroke
			(width 0)
			(type default)
		)
	)
	(wire
		(pts
			(xy 76.2 62.23) (xy 76.2 74.93)
		)
		(stroke
			(width 0)
			(type default)
		)
	)
	(wire
		(pts
			(xy 74.93 54.61) (xy 95.25 54.61)
		)
		(stroke
			(width 0)
			(type default)
		)
	)
	(wire
		(pts
			(xy 176.53 193.04) (xy 176.53 194.31)
		)
		(stroke
			(width 0)
			(type default)
		)
	)
	(wire
		(pts
			(xy 60.96 146.05) (xy 60.96 143.51)
		)
		(stroke
			(width 0)
			(type default)
		)
	)
	(wire
		(pts
			(xy 212.09 241.3) (xy 220.98 241.3)
		)
		(stroke
			(width 0)
			(type default)
		)
	)
	(wire
		(pts
			(xy 30.48 220.98) (xy 41.91 220.98)
		)
		(stroke
			(width 0)
			(type default)
		)
	)
	(bus
		(pts
			(xy 154.94 153.67) (xy 154.94 156.21)
		)
		(stroke
			(width 0)
			(type default)
		)
	)
	(wire
		(pts
			(xy 196.85 193.04) (xy 196.85 194.31)
		)
		(stroke
			(width 0)
			(type default)
		)
	)
	(wire
		(pts
			(xy 170.18 118.11) (xy 168.91 118.11)
		)
		(stroke
			(width 0)
			(type default)
		)
	)
	(wire
		(pts
			(xy 39.37 215.9) (xy 39.37 227.33)
		)
		(stroke
			(width 0)
			(type default)
		)
	)
	(bus
		(pts
			(xy 331.47 60.96) (xy 331.47 63.5)
		)
		(stroke
			(width 0)
			(type default)
		)
	)
	(bus
		(pts
			(xy 219.71 24.13) (xy 219.71 41.91)
		)
		(stroke
			(width 0)
			(type default)
		)
	)
	(polyline
		(pts
			(xy 236.22 82.55) (xy 262.89 82.55)
		)
		(stroke
			(width 0)
			(type default)
		)
	)
	(wire
		(pts
			(xy 74.93 97.79) (xy 91.44 97.79)
		)
		(stroke
			(width 0)
			(type default)
		)
	)
	(wire
		(pts
			(xy 248.92 143.51) (xy 248.92 147.32)
		)
		(stroke
			(width 0)
			(type default)
		)
	)
	(wire
		(pts
			(xy 68.58 209.55) (xy 69.85 209.55)
		)
		(stroke
			(width 0)
			(type default)
		)
	)
	(wire
		(pts
			(xy 60.96 69.85) (xy 44.45 69.85)
		)
		(stroke
			(width 0)
			(type default)
		)
	)
	(wire
		(pts
			(xy 168.91 140.97) (xy 168.91 148.59)
		)
		(stroke
			(width 0)
			(type default)
		)
	)
	(wire
		(pts
			(xy 154.94 85.09) (xy 170.18 85.09)
		)
		(stroke
			(width 0)
			(type default)
		)
	)
	(wire
		(pts
			(xy 134.62 223.52) (xy 134.62 224.79)
		)
		(stroke
			(width 0)
			(type default)
		)
	)
	(wire
		(pts
			(xy 184.15 156.21) (xy 185.42 156.21)
		)
		(stroke
			(width 0)
			(type default)
		)
	)
	(wire
		(pts
			(xy 38.1 144.78) (xy 38.1 146.05)
		)
		(stroke
			(width 0)
			(type default)
		)
	)
	(wire
		(pts
			(xy 266.7 127) (xy 266.7 128.27)
		)
		(stroke
			(width 0)
			(type default)
		)
	)
	(bus
		(pts
			(xy 200.66 85.09) (xy 201.93 85.09)
		)
		(stroke
			(width 0)
			(type default)
		)
	)
	(wire
		(pts
			(xy 161.29 107.95) (xy 170.18 107.95)
		)
		(stroke
			(width 0)
			(type default)
		)
	)
	(wire
		(pts
			(xy 377.19 35.56) (xy 391.16 35.56)
		)
		(stroke
			(width 0)
			(type default)
		)
	)
	(wire
		(pts
			(xy 40.64 63.5) (xy 40.64 64.77)
		)
		(stroke
			(width 0)
			(type default)
		)
	)
	(wire
		(pts
			(xy 170.18 110.49) (xy 168.91 110.49)
		)
		(stroke
			(width 0)
			(type default)
		)
	)
	(wire
		(pts
			(xy 293.37 93.98) (xy 293.37 95.25)
		)
		(stroke
			(width 0)
			(type default)
		)
	)
	(wire
		(pts
			(xy 189.23 222.25) (xy 189.23 223.52)
		)
		(stroke
			(width 0)
			(type default)
		)
	)
	(bus
		(pts
			(xy 39.37 107.95) (xy 39.37 125.73)
		)
		(stroke
			(width 0)
			(type default)
		)
	)
	(wire
		(pts
			(xy 132.08 223.52) (xy 132.08 224.79)
		)
		(stroke
			(width 0)
			(type default)
		)
	)
	(wire
		(pts
			(xy 280.67 222.25) (xy 270.51 222.25)
		)
		(stroke
			(width 0)
			(type default)
		)
	)
	(wire
		(pts
			(xy 184.15 92.71) (xy 198.12 92.71)
		)
		(stroke
			(width 0)
			(type default)
		)
	)
	(wire
		(pts
			(xy 138.43 97.79) (xy 156.21 97.79)
		)
		(stroke
			(width 0)
			(type default)
		)
	)
	(wire
		(pts
			(xy 52.07 198.12) (xy 68.58 198.12)
		)
		(stroke
			(width 0)
			(type default)
		)
	)
	(wire
		(pts
			(xy 74.93 64.77) (xy 91.44 64.77)
		)
		(stroke
			(width 0)
			(type default)
		)
	)
	(wire
		(pts
			(xy 41.91 146.05) (xy 60.96 146.05)
		)
		(stroke
			(width 0)
			(type default)
		)
	)
	(bus
		(pts
			(xy 135.89 153.67) (xy 135.89 151.13)
		)
		(stroke
			(width 0)
			(type default)
		)
	)
	(bus
		(pts
			(xy 200.66 52.07) (xy 200.66 57.15)
		)
		(stroke
			(width 0)
			(type default)
		)
	)
	(wire
		(pts
			(xy 350.52 227.33) (xy 358.14 227.33)
		)
		(stroke
			(width 0)
			(type default)
		)
	)
	(wire
		(pts
			(xy 123.19 245.11) (xy 123.19 246.38)
		)
		(stroke
			(width 0)
			(type default)
		)
	)
	(wire
		(pts
			(xy 184.15 95.25) (xy 198.12 95.25)
		)
		(stroke
			(width 0)
			(type default)
		)
	)
	(wire
		(pts
			(xy 184.15 67.31) (xy 198.12 67.31)
		)
		(stroke
			(width 0)
			(type default)
		)
	)
	(polyline
		(pts
			(xy 232.41 229.87) (xy 232.41 284.48)
		)
		(stroke
			(width 0)
			(type default)
		)
	)
	(wire
		(pts
			(xy 269.24 40.64) (xy 278.13 40.64)
		)
		(stroke
			(width 0)
			(type default)
		)
	)
	(wire
		(pts
			(xy 168.91 110.49) (xy 168.91 118.11)
		)
		(stroke
			(width 0)
			(type default)
		)
	)
	(wire
		(pts
			(xy 74.93 110.49) (xy 91.44 110.49)
		)
		(stroke
			(width 0)
			(type default)
		)
	)
	(wire
		(pts
			(xy 44.45 215.9) (xy 39.37 215.9)
		)
		(stroke
			(width 0)
			(type default)
		)
	)
	(wire
		(pts
			(xy 25.4 140.97) (xy 25.4 143.51)
		)
		(stroke
			(width 0)
			(type default)
		)
	)
	(wire
		(pts
			(xy 340.36 161.29) (xy 340.36 160.02)
		)
		(stroke
			(width 0)
			(type default)
		)
	)
	(wire
		(pts
			(xy 184.15 57.15) (xy 185.42 57.15)
		)
		(stroke
			(width 0)
			(type default)
		)
	)
	(bus
		(pts
			(xy 135.89 113.03) (xy 135.89 114.3)
		)
		(stroke
			(width 0)
			(type default)
		)
	)
	(bus
		(pts
			(xy 200.66 64.77) (xy 200.66 67.31)
		)
		(stroke
			(width 0)
			(type default)
		)
	)
	(wire
		(pts
			(xy 196.85 205.74) (xy 196.85 208.28)
		)
		(stroke
			(width 0)
			(type default)
		)
	)
	(wire
		(pts
			(xy 161.29 115.57) (xy 170.18 115.57)
		)
		(stroke
			(width 0)
			(type default)
		)
	)
	(bus
		(pts
			(xy 135.89 31.75) (xy 135.89 41.91)
		)
		(stroke
			(width 0)
			(type default)
		)
	)
	(wire
		(pts
			(xy 138.43 128.27) (xy 170.18 128.27)
		)
		(stroke
			(width 0)
			(type default)
		)
	)
	(wire
		(pts
			(xy 350.52 220.98) (xy 350.52 218.44)
		)
		(stroke
			(width 0)
			(type default)
		)
	)
	(bus
		(pts
			(xy 96.52 102.87) (xy 93.98 102.87)
		)
		(stroke
			(width 0)
			(type default)
		)
	)
	(wire
		(pts
			(xy 248.92 50.8) (xy 278.13 50.8)
		)
		(stroke
			(width 0)
			(type default)
		)
	)
	(wire
		(pts
			(xy 250.19 222.25) (xy 234.95 222.25)
		)
		(stroke
			(width 0)
			(type default)
		)
	)
	(wire
		(pts
			(xy 248.92 147.32) (xy 250.19 147.32)
		)
		(stroke
			(width 0)
			(type default)
		)
	)
	(wire
		(pts
			(xy 170.18 148.59) (xy 168.91 148.59)
		)
		(stroke
			(width 0)
			(type default)
		)
	)
	(bus
		(pts
			(xy 393.7 88.9) (xy 393.7 91.44)
		)
		(stroke
			(width 0)
			(type default)
		)
	)
	(polyline
		(pts
			(xy 347.98 101.6) (xy 347.98 93.98)
		)
		(stroke
			(width 0)
			(type default)
		)
	)
	(wire
		(pts
			(xy 60.96 90.17) (xy 44.45 90.17)
		)
		(stroke
			(width 0)
			(type default)
		)
	)
	(wire
		(pts
			(xy 39.37 227.33) (xy 39.37 241.3)
		)
		(stroke
			(width 0)
			(type default)
		)
	)
	(bus
		(pts
			(xy 393.7 35.56) (xy 393.7 38.1)
		)
		(stroke
			(width 0)
			(type default)
		)
	)
	(wire
		(pts
			(xy 184.15 125.73) (xy 185.42 125.73)
		)
		(stroke
			(width 0)
			(type default)
		)
	)
	(wire
		(pts
			(xy 184.15 107.95) (xy 196.85 107.95)
		)
		(stroke
			(width 0)
			(type default)
		)
	)
	(wire
		(pts
			(xy 35.56 251.46) (xy 38.1 251.46)
		)
		(stroke
			(width 0)
			(type default)
		)
	)
	(polyline
		(pts
			(xy 151.13 86.36) (xy 151.13 87.63)
		)
		(stroke
			(width 0)
			(type default)
		)
	)
	(wire
		(pts
			(xy 161.29 113.03) (xy 170.18 113.03)
		)
		(stroke
			(width 0)
			(type default)
		)
	)
	(wire
		(pts
			(xy 114.3 208.28) (xy 114.3 209.55)
		)
		(stroke
			(width 0)
			(type default)
		)
	)
	(bus
		(pts
			(xy 135.89 87.63) (xy 135.89 90.17)
		)
		(stroke
			(width 0)
			(type default)
		)
	)
	(wire
		(pts
			(xy 74.93 69.85) (xy 91.44 69.85)
		)
		(stroke
			(width 0)
			(type default)
		)
	)
	(wire
		(pts
			(xy 107.95 266.7) (xy 95.25 266.7)
		)
		(stroke
			(width 0)
			(type default)
		)
	)
	(wire
		(pts
			(xy 184.15 90.17) (xy 198.12 90.17)
		)
		(stroke
			(width 0)
			(type default)
		)
	)
	(bus
		(pts
			(xy 283.21 214.63) (xy 283.21 219.71)
		)
		(stroke
			(width 0)
			(type default)
		)
	)
	(wire
		(pts
			(xy 25.4 146.05) (xy 26.67 146.05)
		)
		(stroke
			(width 0)
			(type default)
		)
	)
	(wire
		(pts
			(xy 195.58 241.3) (xy 207.01 241.3)
		)
		(stroke
			(width 0)
			(type default)
		)
	)
	(bus
		(pts
			(xy 219.71 41.91) (xy 219.71 102.87)
		)
		(stroke
			(width 0)
			(type default)
		)
	)
	(wire
		(pts
			(xy 168.91 148.59) (xy 168.91 156.21)
		)
		(stroke
			(width 0)
			(type default)
		)
	)
	(wire
		(pts
			(xy 138.43 44.45) (xy 170.18 44.45)
		)
		(stroke
			(width 0)
			(type default)
		)
	)
	(wire
		(pts
			(xy 74.93 107.95) (xy 76.2 107.95)
		)
		(stroke
			(width 0)
			(type default)
		)
	)
	(wire
		(pts
			(xy 138.43 62.23) (xy 170.18 62.23)
		)
		(stroke
			(width 0)
			(type default)
		)
	)
	(bus
		(pts
			(xy 93.98 107.95) (xy 93.98 110.49)
		)
		(stroke
			(width 0)
			(type default)
		)
	)
	(bus
		(pts
			(xy 97.79 44.45) (xy 97.79 49.53)
		)
		(stroke
			(width 0)
			(type default)
		)
	)
	(wire
		(pts
			(xy 184.15 52.07) (xy 198.12 52.07)
		)
		(stroke
			(width 0)
			(type default)
		)
	)
	(wire
		(pts
			(xy 60.96 80.01) (xy 44.45 80.01)
		)
		(stroke
			(width 0)
			(type default)
		)
	)
	(wire
		(pts
			(xy 247.65 62.23) (xy 247.65 66.04)
		)
		(stroke
			(width 0)
			(type default)
		)
	)
	(wire
		(pts
			(xy 59.69 41.91) (xy 59.69 49.53)
		)
		(stroke
			(width 0)
			(type default)
		)
	)
	(wire
		(pts
			(xy 76.2 74.93) (xy 76.2 100.33)
		)
		(stroke
			(width 0)
			(type default)
		)
	)
	(wire
		(pts
			(xy 190.5 266.7) (xy 190.5 270.51)
		)
		(stroke
			(width 0)
			(type default)
		)
	)
	(wire
		(pts
			(xy 170.18 156.21) (xy 168.91 156.21)
		)
		(stroke
			(width 0)
			(type default)
		)
	)
	(wire
		(pts
			(xy 170.18 72.39) (xy 168.91 72.39)
		)
		(stroke
			(width 0)
			(type default)
		)
	)
	(wire
		(pts
			(xy 59.69 97.79) (xy 59.69 107.95)
		)
		(stroke
			(width 0)
			(type default)
		)
	)
	(wire
		(pts
			(xy 189.23 271.78) (xy 189.23 270.51)
		)
		(stroke
			(width 0)
			(type default)
		)
	)
	(wire
		(pts
			(xy 114.3 201.93) (xy 114.3 203.2)
		)
		(stroke
			(width 0)
			(type default)
		)
	)
	(wire
		(pts
			(xy 270.51 212.09) (xy 271.78 212.09)
		)
		(stroke
			(width 0)
			(type default)
		)
	)
	(wire
		(pts
			(xy 74.93 74.93) (xy 76.2 74.93)
		)
		(stroke
			(width 0)
			(type default)
		)
	)
	(wire
		(pts
			(xy 138.43 59.69) (xy 170.18 59.69)
		)
		(stroke
			(width 0)
			(type default)
		)
	)
	(wire
		(pts
			(xy 41.91 135.89) (xy 60.96 135.89)
		)
		(stroke
			(width 0)
			(type default)
		)
	)
	(bus
		(pts
			(xy 332.74 58.42) (xy 331.47 58.42)
		)
		(stroke
			(width 0)
			(type default)
		)
	)
	(wire
		(pts
			(xy 250.19 162.56) (xy 236.22 162.56)
		)
		(stroke
			(width 0)
			(type default)
		)
	)
	(wire
		(pts
			(xy 271.78 237.49) (xy 270.51 237.49)
		)
		(stroke
			(width 0)
			(type default)
		)
	)
	(wire
		(pts
			(xy 68.58 233.68) (xy 68.58 232.41)
		)
		(stroke
			(width 0)
			(type default)
		)
	)
	(polyline
		(pts
			(xy 303.53 93.98) (xy 303.53 101.6)
		)
		(stroke
			(width 0)
			(type default)
		)
	)
	(wire
		(pts
			(xy 76.2 49.53) (xy 76.2 62.23)
		)
		(stroke
			(width 0)
			(type default)
		)
	)
	(wire
		(pts
			(xy 60.96 41.91) (xy 59.69 41.91)
		)
		(stroke
			(width 0)
			(type default)
		)
	)
	(wire
		(pts
			(xy 30.48 209.55) (xy 41.91 209.55)
		)
		(stroke
			(width 0)
			(type default)
		)
	)
	(wire
		(pts
			(xy 377.19 71.12) (xy 391.16 71.12)
		)
		(stroke
			(width 0)
			(type default)
		)
	)
	(bus
		(pts
			(xy 332.74 66.04) (xy 331.47 66.04)
		)
		(stroke
			(width 0)
			(type default)
		)
	)
	(wire
		(pts
			(xy 30.48 198.12) (xy 30.48 209.55)
		)
		(stroke
			(width 0)
			(type default)
		)
	)
	(wire
		(pts
			(xy 240.03 68.58) (xy 278.13 68.58)
		)
		(stroke
			(width 0)
			(type default)
		)
	)
	(wire
		(pts
			(xy 184.15 36.83) (xy 198.12 36.83)
		)
		(stroke
			(width 0)
			(type default)
		)
	)
	(wire
		(pts
			(xy 255.27 62.23) (xy 255.27 63.5)
		)
		(stroke
			(width 0)
			(type default)
		)
	)
	(bus
		(pts
			(xy 393.7 91.44) (xy 393.7 93.98)
		)
		(stroke
			(width 0)
			(type default)
		)
	)
	(wire
		(pts
			(xy 138.43 90.17) (xy 156.21 90.17)
		)
		(stroke
			(width 0)
			(type default)
		)
	)
	(wire
		(pts
			(xy 303.53 50.8) (xy 328.93 50.8)
		)
		(stroke
			(width 0)
			(type default)
		)
	)
	(wire
		(pts
			(xy 60.96 130.81) (xy 58.42 130.81)
		)
		(stroke
			(width 0)
			(type default)
		)
	)
	(polyline
		(pts
			(xy 236.22 82.55) (xy 236.22 106.68)
		)
		(stroke
			(width 0)
			(type default)
		)
	)
	(polyline
		(pts
			(xy 304.8 109.22) (xy 304.8 252.73)
		)
		(stroke
			(width 0)
			(type default)
		)
	)
	(wire
		(pts
			(xy 161.29 90.17) (xy 170.18 90.17)
		)
		(stroke
			(width 0)
			(type default)
		)
	)
	(wire
		(pts
			(xy 43.18 158.75) (xy 60.96 158.75)
		)
		(stroke
			(width 0)
			(type default)
		)
	)
	(wire
		(pts
			(xy 80.01 129.54) (xy 80.01 130.81)
		)
		(stroke
			(width 0)
			(type default)
		)
	)
	(wire
		(pts
			(xy 340.36 133.35) (xy 341.63 133.35)
		)
		(stroke
			(width 0)
			(type default)
		)
	)
	(wire
		(pts
			(xy 271.78 147.32) (xy 271.78 144.78)
		)
		(stroke
			(width 0)
			(type default)
		)
	)
	(wire
		(pts
			(xy 251.46 36.83) (xy 254 36.83)
		)
		(stroke
			(width 0)
			(type default)
		)
	)
	(wire
		(pts
			(xy 138.43 105.41) (xy 156.21 105.41)
		)
		(stroke
			(width 0)
			(type default)
		)
	)
	(bus
		(pts
			(xy 393.7 48.26) (xy 393.7 50.8)
		)
		(stroke
			(width 0)
			(type default)
		)
	)
	(bus
		(pts
			(xy 283.21 160.02) (xy 283.21 165.1)
		)
		(stroke
			(width 0)
			(type default)
		)
	)
	(wire
		(pts
			(xy 176.53 199.39) (xy 176.53 200.66)
		)
		(stroke
			(width 0)
			(type default)
		)
	)
	(bus
		(pts
			(xy 154.94 156.21) (xy 154.94 171.45)
		)
		(stroke
			(width 0)
			(type default)
		)
	)
	(wire
		(pts
			(xy 134.62 199.39) (xy 132.08 199.39)
		)
		(stroke
			(width 0)
			(type default)
		)
	)
	(wire
		(pts
			(xy 41.91 144.78) (xy 41.91 146.05)
		)
		(stroke
			(width 0)
			(type default)
		)
	)
	(bus
		(pts
			(xy 93.98 102.87) (xy 93.98 107.95)
		)
		(stroke
			(width 0)
			(type default)
		)
	)
	(wire
		(pts
			(xy 280.67 232.41) (xy 270.51 232.41)
		)
		(stroke
			(width 0)
			(type default)
		)
	)
	(wire
		(pts
			(xy 365.76 218.44) (xy 379.73 218.44)
		)
		(stroke
			(width 0)
			(type default)
		)
	)
	(wire
		(pts
			(xy 44.45 241.3) (xy 44.45 243.84)
		)
		(stroke
			(width 0)
			(type default)
		)
	)
	(wire
		(pts
			(xy 377.19 73.66) (xy 391.16 73.66)
		)
		(stroke
			(width 0)
			(type default)
		)
	)
	(wire
		(pts
			(xy 80.01 135.89) (xy 80.01 133.35)
		)
		(stroke
			(width 0)
			(type default)
		)
	)
	(bus
		(pts
			(xy 72.39 207.01) (xy 72.39 195.58)
		)
		(stroke
			(width 0)
			(type default)
		)
	)
	(wire
		(pts
			(xy 377.19 81.28) (xy 391.16 81.28)
		)
		(stroke
			(width 0)
			(type default)
		)
	)
	(bus
		(pts
			(xy 200.66 143.51) (xy 200.66 148.59)
		)
		(stroke
			(width 0)
			(type default)
		)
	)
	(bus
		(pts
			(xy 135.89 41.91) (xy 135.89 44.45)
		)
		(stroke
			(width 0)
			(type default)
		)
	)
	(bus
		(pts
			(xy 135.89 52.07) (xy 135.89 57.15)
		)
		(stroke
			(width 0)
			(type default)
		)
	)
	(wire
		(pts
			(xy 184.15 80.01) (xy 185.42 80.01)
		)
		(stroke
			(width 0)
			(type default)
		)
	)
	(wire
		(pts
			(xy 184.15 153.67) (xy 198.12 153.67)
		)
		(stroke
			(width 0)
			(type default)
		)
	)
	(wire
		(pts
			(xy 168.91 156.21) (xy 168.91 165.1)
		)
		(stroke
			(width 0)
			(type default)
		)
	)
	(wire
		(pts
			(xy 377.19 43.18) (xy 391.16 43.18)
		)
		(stroke
			(width 0)
			(type default)
		)
	)
	(wire
		(pts
			(xy 215.9 195.58) (xy 218.44 195.58)
		)
		(stroke
			(width 0)
			(type default)
		)
	)
	(wire
		(pts
			(xy 154.94 82.55) (xy 170.18 82.55)
		)
		(stroke
			(width 0)
			(type default)
		)
	)
	(bus
		(pts
			(xy 201.93 49.53) (xy 200.66 49.53)
		)
		(stroke
			(width 0)
			(type default)
		)
	)
	(wire
		(pts
			(xy 185.42 41.91) (xy 185.42 49.53)
		)
		(stroke
			(width 0)
			(type default)
		)
	)
	(wire
		(pts
			(xy 184.15 110.49) (xy 185.42 110.49)
		)
		(stroke
			(width 0)
			(type default)
		)
	)
	(bus
		(pts
			(xy 200.66 133.35) (xy 200.66 135.89)
		)
		(stroke
			(width 0)
			(type default)
		)
	)
	(bus
		(pts
			(xy 41.91 24.13) (xy 97.79 24.13)
		)
		(stroke
			(width 0)
			(type default)
		)
	)
	(bus
		(pts
			(xy 200.66 59.69) (xy 200.66 64.77)
		)
		(stroke
			(width 0)
			(type default)
		)
	)
	(bus
		(pts
			(xy 104.14 166.37) (xy 104.14 168.91)
		)
		(stroke
			(width 0)
			(type default)
		)
	)
	(bus
		(pts
			(xy 200.66 31.75) (xy 200.66 34.29)
		)
		(stroke
			(width 0)
			(type default)
		)
	)
	(bus
		(pts
			(xy 393.7 50.8) (xy 393.7 53.34)
		)
		(stroke
			(width 0)
			(type default)
		)
	)
	(wire
		(pts
			(xy 189.23 276.86) (xy 189.23 281.94)
		)
		(stroke
			(width 0)
			(type default)
		)
	)
	(wire
		(pts
			(xy 134.62 208.28) (xy 134.62 209.55)
		)
		(stroke
			(width 0)
			(type default)
		)
	)
	(wire
		(pts
			(xy 138.43 100.33) (xy 156.21 100.33)
		)
		(stroke
			(width 0)
			(type default)
		)
	)
	(wire
		(pts
			(xy 185.42 156.21) (xy 185.42 165.1)
		)
		(stroke
			(width 0)
			(type default)
		)
	)
	(wire
		(pts
			(xy 30.48 198.12) (xy 41.91 198.12)
		)
		(stroke
			(width 0)
			(type default)
		)
	)
	(bus
		(pts
			(xy 152.4 67.31) (xy 152.4 72.39)
		)
		(stroke
			(width 0)
			(type default)
		)
	)
	(wire
		(pts
			(xy 60.96 92.71) (xy 44.45 92.71)
		)
		(stroke
			(width 0)
			(type default)
		)
	)
	(wire
		(pts
			(xy 60.96 102.87) (xy 44.45 102.87)
		)
		(stroke
			(width 0)
			(type default)
		)
	)
	(bus
		(pts
			(xy 104.14 165.1) (xy 104.14 166.37)
		)
		(stroke
			(width 0)
			(type default)
		)
	)
	(wire
		(pts
			(xy 138.43 156.21) (xy 147.32 156.21)
		)
		(stroke
			(width 0)
			(type default)
		)
	)
	(wire
		(pts
			(xy 170.18 80.01) (xy 168.91 80.01)
		)
		(stroke
			(width 0)
			(type default)
		)
	)
	(wire
		(pts
			(xy 170.18 125.73) (xy 168.91 125.73)
		)
		(stroke
			(width 0)
			(type default)
		)
	)
	(wire
		(pts
			(xy 30.48 251.46) (xy 35.56 251.46)
		)
		(stroke
			(width 0)
			(type default)
		)
	)
	(wire
		(pts
			(xy 377.19 50.8) (xy 391.16 50.8)
		)
		(stroke
			(width 0)
			(type default)
		)
	)
	(wire
		(pts
			(xy 148.59 190.5) (xy 148.59 194.31)
		)
		(stroke
			(width 0)
			(type default)
		)
	)
	(wire
		(pts
			(xy 74.93 49.53) (xy 76.2 49.53)
		)
		(stroke
			(width 0)
			(type default)
		)
	)
	(wire
		(pts
			(xy 184.15 105.41) (xy 196.85 105.41)
		)
		(stroke
			(width 0)
			(type default)
		)
	)
	(wire
		(pts
			(xy 168.91 213.36) (xy 168.91 215.9)
		)
		(stroke
			(width 0)
			(type default)
		)
	)
	(wire
		(pts
			(xy 74.93 52.07) (xy 95.25 52.07)
		)
		(stroke
			(width 0)
			(type default)
		)
	)
	(wire
		(pts
			(xy 251.46 36.83) (xy 248.92 36.83)
		)
		(stroke
			(width 0)
			(type default)
		)
	)
	(polyline
		(pts
			(xy 304.8 191.77) (xy 407.67 191.77)
		)
		(stroke
			(width 0)
			(type default)
		)
	)
	(wire
		(pts
			(xy 240.03 68.58) (xy 240.03 69.85)
		)
		(stroke
			(width 0)
			(type default)
		)
	)
	(wire
		(pts
			(xy 349.25 245.11) (xy 349.25 243.84)
		)
		(stroke
			(width 0)
			(type default)
		)
	)
	(bus
		(pts
			(xy 200.66 72.39) (xy 200.66 74.93)
		)
		(stroke
			(width 0)
			(type default)
		)
	)
	(wire
		(pts
			(xy 161.29 92.71) (xy 170.18 92.71)
		)
		(stroke
			(width 0)
			(type default)
		)
	)
	(wire
		(pts
			(xy 303.53 73.66) (xy 306.07 73.66)
		)
		(stroke
			(width 0)
			(type default)
		)
	)
	(wire
		(pts
			(xy 218.44 186.69) (xy 218.44 187.96)
		)
		(stroke
			(width 0)
			(type default)
		)
	)
	(wire
		(pts
			(xy 170.18 87.63) (xy 168.91 87.63)
		)
		(stroke
			(width 0)
			(type default)
		)
	)
	(wire
		(pts
			(xy 184.15 135.89) (xy 198.12 135.89)
		)
		(stroke
			(width 0)
			(type default)
		)
	)
	(wire
		(pts
			(xy 76.2 115.57) (xy 76.2 123.19)
		)
		(stroke
			(width 0)
			(type default)
		)
	)
	(bus
		(pts
			(xy 135.89 102.87) (xy 135.89 105.41)
		)
		(stroke
			(width 0)
			(type default)
		)
	)
	(wire
		(pts
			(xy 184.15 100.33) (xy 196.85 100.33)
		)
		(stroke
			(width 0)
			(type default)
		)
	)
	(bus
		(pts
			(xy 283.21 149.86) (xy 283.21 154.94)
		)
		(stroke
			(width 0)
			(type default)
		)
	)
	(polyline
		(pts
			(xy 163.83 86.36) (xy 151.13 86.36)
		)
		(stroke
			(width 0)
			(type default)
		)
	)
	(wire
		(pts
			(xy 187.96 215.9) (xy 189.23 215.9)
		)
		(stroke
			(width 0)
			(type default)
		)
	)
	(wire
		(pts
			(xy 74.93 100.33) (xy 76.2 100.33)
		)
		(stroke
			(width 0)
			(type default)
		)
	)
	(wire
		(pts
			(xy 377.19 45.72) (xy 391.16 45.72)
		)
		(stroke
			(width 0)
			(type default)
		)
	)
	(bus
		(pts
			(xy 200.66 92.71) (xy 200.66 90.17)
		)
		(stroke
			(width 0)
			(type default)
		)
	)
	(wire
		(pts
			(xy 168.91 87.63) (xy 168.91 95.25)
		)
		(stroke
			(width 0)
			(type default)
		)
	)
	(bus
		(pts
			(xy 135.89 151.13) (xy 135.89 148.59)
		)
		(stroke
			(width 0)
			(type default)
		)
	)
	(wire
		(pts
			(xy 167.64 215.9) (xy 168.91 215.9)
		)
		(stroke
			(width 0)
			(type default)
		)
	)
	(wire
		(pts
			(xy 74.93 39.37) (xy 95.25 39.37)
		)
		(stroke
			(width 0)
			(type default)
		)
	)
	(bus
		(pts
			(xy 72.39 229.87) (xy 72.39 218.44)
		)
		(stroke
			(width 0)
			(type default)
		)
	)
	(wire
		(pts
			(xy 139.7 271.78) (xy 139.7 278.13)
		)
		(stroke
			(width 0)
			(type default)
		)
	)
	(wire
		(pts
			(xy 240.03 76.2) (xy 240.03 74.93)
		)
		(stroke
			(width 0)
			(type default)
		)
	)
	(wire
		(pts
			(xy 255.27 55.88) (xy 255.27 57.15)
		)
		(stroke
			(width 0)
			(type default)
		)
	)
	(wire
		(pts
			(xy 184.15 252.73) (xy 189.23 252.73)
		)
		(stroke
			(width 0)
			(type default)
		)
	)
	(wire
		(pts
			(xy 247.65 66.04) (xy 247.65 69.85)
		)
		(stroke
			(width 0)
			(type default)
		)
	)
	(wire
		(pts
			(xy 142.24 238.76) (xy 134.62 238.76)
		)
		(stroke
			(width 0)
			(type default)
		)
	)
	(wire
		(pts
			(xy 250.19 152.4) (xy 236.22 152.4)
		)
		(stroke
			(width 0)
			(type default)
		)
	)
	(wire
		(pts
			(xy 303.53 63.5) (xy 328.93 63.5)
		)
		(stroke
			(width 0)
			(type default)
		)
	)
	(wire
		(pts
			(xy 80.01 138.43) (xy 74.93 138.43)
		)
		(stroke
			(width 0)
			(type default)
		)
	)
	(bus
		(pts
			(xy 135.89 125.73) (xy 135.89 128.27)
		)
		(stroke
			(width 0)
			(type default)
		)
	)
	(bus
		(pts
			(xy 393.7 20.32) (xy 393.7 22.86)
		)
		(stroke
			(width 0)
			(type default)
		)
	)
	(wire
		(pts
			(xy 44.45 227.33) (xy 39.37 227.33)
		)
		(stroke
			(width 0)
			(type default)
		)
	)
	(wire
		(pts
			(xy 377.19 33.02) (xy 391.16 33.02)
		)
		(stroke
			(width 0)
			(type default)
		)
	)
	(bus
		(pts
			(xy 200.66 151.13) (xy 200.66 171.45)
		)
		(stroke
			(width 0)
			(type default)
		)
	)
	(wire
		(pts
			(xy 74.93 62.23) (xy 76.2 62.23)
		)
		(stroke
			(width 0)
			(type default)
		)
	)
	(polyline
		(pts
			(xy 303.53 101.6) (xy 347.98 101.6)
		)
		(stroke
			(width 0)
			(type default)
		)
	)
	(wire
		(pts
			(xy 377.19 38.1) (xy 391.16 38.1)
		)
		(stroke
			(width 0)
			(type default)
		)
	)
	(wire
		(pts
			(xy 377.19 68.58) (xy 391.16 68.58)
		)
		(stroke
			(width 0)
			(type default)
		)
	)
	(wire
		(pts
			(xy 170.18 64.77) (xy 168.91 64.77)
		)
		(stroke
			(width 0)
			(type default)
		)
	)
	(wire
		(pts
			(xy 218.44 193.04) (xy 218.44 195.58)
		)
		(stroke
			(width 0)
			(type default)
		)
	)
	(wire
		(pts
			(xy 377.19 66.04) (xy 391.16 66.04)
		)
		(stroke
			(width 0)
			(type default)
		)
	)
	(wire
		(pts
			(xy 59.69 49.53) (xy 59.69 59.69)
		)
		(stroke
			(width 0)
			(type default)
		)
	)
	(bus
		(pts
			(xy 135.89 24.13) (xy 135.89 31.75)
		)
		(stroke
			(width 0)
			(type default)
		)
	)
	(bus
		(pts
			(xy 200.66 87.63) (xy 200.66 85.09)
		)
		(stroke
			(width 0)
			(type default)
		)
	)
	(wire
		(pts
			(xy 59.69 115.57) (xy 59.69 125.73)
		)
		(stroke
			(width 0)
			(type default)
		)
	)
	(bus
		(pts
			(xy 393.7 86.36) (xy 393.7 88.9)
		)
		(stroke
			(width 0)
			(type default)
		)
	)
	(wire
		(pts
			(xy 250.19 227.33) (xy 234.95 227.33)
		)
		(stroke
			(width 0)
			(type default)
		)
	)
	(wire
		(pts
			(xy 303.53 58.42) (xy 328.93 58.42)
		)
		(stroke
			(width 0)
			(type default)
		)
	)
	(bus
		(pts
			(xy 135.89 118.11) (xy 135.89 120.65)
		)
		(stroke
			(width 0)
			(type default)
		)
	)
	(wire
		(pts
			(xy 80.01 135.89) (xy 74.93 135.89)
		)
		(stroke
			(width 0)
			(type default)
		)
	)
	(bus
		(pts
			(xy 283.21 224.79) (xy 284.48 224.79)
		)
		(stroke
			(width 0)
			(type default)
		)
	)
	(wire
		(pts
			(xy 248.92 172.72) (xy 248.92 147.32)
		)
		(stroke
			(width 0)
			(type default)
		)
	)
	(wire
		(pts
			(xy 303.53 43.18) (xy 306.07 43.18)
		)
		(stroke
			(width 0)
			(type default)
		)
	)
	(bus
		(pts
			(xy 93.98 110.49) (xy 93.98 115.57)
		)
		(stroke
			(width 0)
			(type default)
		)
	)
	(wire
		(pts
			(xy 59.69 156.21) (xy 59.69 163.83)
		)
		(stroke
			(width 0)
			(type default)
		)
	)
	(wire
		(pts
			(xy 68.58 222.25) (xy 68.58 220.98)
		)
		(stroke
			(width 0)
			(type default)
		)
	)
	(polyline
		(pts
			(xy 205.74 118.11) (xy 205.74 100.33)
		)
		(stroke
			(width 0)
			(type default)
		)
	)
	(wire
		(pts
			(xy 52.07 220.98) (xy 68.58 220.98)
		)
		(stroke
			(width 0)
			(type default)
		)
	)
	(wire
		(pts
			(xy 184.15 102.87) (xy 185.42 102.87)
		)
		(stroke
			(width 0)
			(type default)
		)
	)
	(wire
		(pts
			(xy 227.33 219.71) (xy 227.33 220.98)
		)
		(stroke
			(width 0)
			(type default)
		)
	)
	(wire
		(pts
			(xy 377.19 48.26) (xy 391.16 48.26)
		)
		(stroke
			(width 0)
			(type default)
		)
	)
	(bus
		(pts
			(xy 190.5 238.76) (xy 193.04 238.76)
		)
		(stroke
			(width 0)
			(type default)
		)
	)
	(wire
		(pts
			(xy 76.2 100.33) (xy 76.2 107.95)
		)
		(stroke
			(width 0)
			(type default)
		)
	)
	(wire
		(pts
			(xy 350.52 227.33) (xy 350.52 226.06)
		)
		(stroke
			(width 0)
			(type default)
		)
	)
	(wire
		(pts
			(xy 52.07 209.55) (xy 68.58 209.55)
		)
		(stroke
			(width 0)
			(type default)
		)
	)
	(wire
		(pts
			(xy 349.25 237.49) (xy 349.25 238.76)
		)
		(stroke
			(width 0)
			(type default)
		)
	)
	(wire
		(pts
			(xy 260.35 262.89) (xy 260.35 264.16)
		)
		(stroke
			(width 0)
			(type default)
		)
	)
	(wire
		(pts
			(xy 114.3 245.11) (xy 114.3 246.38)
		)
		(stroke
			(width 0)
			(type default)
		)
	)
	(polyline
		(pts
			(xy 232.41 12.7) (xy 232.41 179.07)
		)
		(stroke
			(width 0)
			(type default)
		)
	)
	(wire
		(pts
			(xy 154.94 74.93) (xy 170.18 74.93)
		)
		(stroke
			(width 0)
			(type default)
		)
	)
	(wire
		(pts
			(xy 134.62 198.12) (xy 134.62 199.39)
		)
		(stroke
			(width 0)
			(type default)
		)
	)
	(wire
		(pts
			(xy 248.92 262.89) (xy 260.35 262.89)
		)
		(stroke
			(width 0)
			(type default)
		)
	)
	(wire
		(pts
			(xy 247.65 55.88) (xy 247.65 57.15)
		)
		(stroke
			(width 0)
			(type default)
		)
	)
	(wire
		(pts
			(xy 201.93 105.41) (xy 217.17 105.41)
		)
		(stroke
			(width 0)
			(type default)
		)
	)
	(wire
		(pts
			(xy 76.2 34.29) (xy 76.2 41.91)
		)
		(stroke
			(width 0)
			(type default)
		)
	)
	(wire
		(pts
			(xy 303.53 68.58) (xy 328.93 68.58)
		)
		(stroke
			(width 0)
			(type default)
		)
	)
	(bus
		(pts
			(xy 393.7 22.86) (xy 393.7 25.4)
		)
		(stroke
			(width 0)
			(type default)
		)
	)
	(bus
		(pts
			(xy 200.66 30.48) (xy 200.66 31.75)
		)
		(stroke
			(width 0)
			(type default)
		)
	)
	(wire
		(pts
			(xy 260.35 254) (xy 260.35 256.54)
		)
		(stroke
			(width 0)
			(type default)
		)
	)
	(wire
		(pts
			(xy 280.67 162.56) (xy 270.51 162.56)
		)
		(stroke
			(width 0)
			(type default)
		)
	)
	(wire
		(pts
			(xy 68.58 232.41) (xy 69.85 232.41)
		)
		(stroke
			(width 0)
			(type default)
		)
	)
	(wire
		(pts
			(xy 74.93 90.17) (xy 91.44 90.17)
		)
		(stroke
			(width 0)
			(type default)
		)
	)
	(bus
		(pts
			(xy 152.4 64.77) (xy 152.4 67.31)
		)
		(stroke
			(width 0)
			(type default)
		)
	)
	(bus
		(pts
			(xy 200.66 125.73) (xy 200.66 128.27)
		)
		(stroke
			(width 0)
			(type default)
		)
	)
	(wire
		(pts
			(xy 138.43 120.65) (xy 170.18 120.65)
		)
		(stroke
			(width 0)
			(type default)
		)
	)
	(wire
		(pts
			(xy 303.53 76.2) (xy 312.42 76.2)
		)
		(stroke
			(width 0)
			(type default)
		)
	)
	(polyline
		(pts
			(xy 191.77 100.33) (xy 191.77 118.11)
		)
		(stroke
			(width 0)
			(type default)
		)
	)
	(bus
		(pts
			(xy 219.71 105.41) (xy 219.71 110.49)
		)
		(stroke
			(width 0)
			(type default)
		)
	)
	(wire
		(pts
			(xy 184.15 49.53) (xy 185.42 49.53)
		)
		(stroke
			(width 0)
			(type default)
		)
	)
	(polyline
		(pts
			(xy 303.53 93.98) (xy 347.98 93.98)
		)
		(stroke
			(width 0)
			(type default)
		)
	)
	(wire
		(pts
			(xy 377.19 60.96) (xy 391.16 60.96)
		)
		(stroke
			(width 0)
			(type default)
		)
	)
	(wire
		(pts
			(xy 170.18 57.15) (xy 168.91 57.15)
		)
		(stroke
			(width 0)
			(type default)
		)
	)
	(polyline
		(pts
			(xy 232.41 229.87) (xy 232.41 179.07)
		)
		(stroke
			(width 0)
			(type default)
		)
	)
	(wire
		(pts
			(xy 80.01 156.21) (xy 80.01 168.91)
		)
		(stroke
			(width 0)
			(type default)
		)
	)
	(wire
		(pts
			(xy 68.58 220.98) (xy 69.85 220.98)
		)
		(stroke
			(width 0)
			(type default)
		)
	)
	(wire
		(pts
			(xy 25.4 143.51) (xy 25.4 146.05)
		)
		(stroke
			(width 0)
			(type default)
		)
	)
	(bus
		(pts
			(xy 200.66 74.93) (xy 200.66 80.01)
		)
		(stroke
			(width 0)
			(type default)
		)
	)
	(wire
		(pts
			(xy 377.19 55.88) (xy 391.16 55.88)
		)
		(stroke
			(width 0)
			(type default)
		)
	)
	(wire
		(pts
			(xy 60.96 115.57) (xy 59.69 115.57)
		)
		(stroke
			(width 0)
			(type default)
		)
	)
	(wire
		(pts
			(xy 31.75 146.05) (xy 38.1 146.05)
		)
		(stroke
			(width 0)
			(type default)
		)
	)
	(bus
		(pts
			(xy 97.79 49.53) (xy 97.79 52.07)
		)
		(stroke
			(width 0)
			(type default)
		)
	)
	(wire
		(pts
			(xy 270.51 147.32) (xy 271.78 147.32)
		)
		(stroke
			(width 0)
			(type default)
		)
	)
	(wire
		(pts
			(xy 86.36 168.91) (xy 101.6 168.91)
		)
		(stroke
			(width 0)
			(type default)
		)
	)
	(wire
		(pts
			(xy 377.19 88.9) (xy 391.16 88.9)
		)
		(stroke
			(width 0)
			(type default)
		)
	)
	(wire
		(pts
			(xy 176.53 218.44) (xy 176.53 223.52)
		)
		(stroke
			(width 0)
			(type default)
		)
	)
	(wire
		(pts
			(xy 161.29 105.41) (xy 170.18 105.41)
		)
		(stroke
			(width 0)
			(type default)
		)
	)
	(wire
		(pts
			(xy 168.91 102.87) (xy 168.91 110.49)
		)
		(stroke
			(width 0)
			(type default)
		)
	)
	(wire
		(pts
			(xy 184.15 151.13) (xy 198.12 151.13)
		)
		(stroke
			(width 0)
			(type default)
		)
	)
	(wire
		(pts
			(xy 86.36 171.45) (xy 101.6 171.45)
		)
		(stroke
			(width 0)
			(type default)
		)
	)
	(wire
		(pts
			(xy 36.83 241.3) (xy 39.37 241.3)
		)
		(stroke
			(width 0)
			(type default)
		)
	)
	(wire
		(pts
			(xy 190.5 270.51) (xy 191.77 270.51)
		)
		(stroke
			(width 0)
			(type default)
		)
	)
	(wire
		(pts
			(xy 350.52 218.44) (xy 355.6 218.44)
		)
		(stroke
			(width 0)
			(type default)
		)
	)
	(wire
		(pts
			(xy 377.19 40.64) (xy 391.16 40.64)
		)
		(stroke
			(width 0)
			(type default)
		)
	)
	(wire
		(pts
			(xy 59.69 72.39) (xy 59.69 85.09)
		)
		(stroke
			(width 0)
			(type default)
		)
	)
	(bus
		(pts
			(xy 332.74 43.18) (xy 331.47 43.18)
		)
		(stroke
			(width 0)
			(type default)
		)
	)
	(wire
		(pts
			(xy 250.19 157.48) (xy 236.22 157.48)
		)
		(stroke
			(width 0)
			(type default)
		)
	)
	(wire
		(pts
			(xy 80.01 143.51) (xy 74.93 143.51)
		)
		(stroke
			(width 0)
			(type default)
		)
	)
	(wire
		(pts
			(xy 168.91 133.35) (xy 168.91 140.97)
		)
		(stroke
			(width 0)
			(type default)
		)
	)
	(bus
		(pts
			(xy 39.37 130.81) (xy 39.37 133.35)
		)
		(stroke
			(width 0)
			(type default)
		)
	)
	(wire
		(pts
			(xy 184.15 143.51) (xy 198.12 143.51)
		)
		(stroke
			(width 0)
			(type default)
		)
	)
	(wire
		(pts
			(xy 30.48 193.04) (xy 30.48 198.12)
		)
		(stroke
			(width 0)
			(type default)
		)
	)
	(wire
		(pts
			(xy 340.36 142.24) (xy 341.63 142.24)
		)
		(stroke
			(width 0)
			(type default)
		)
	)
	(bus
		(pts
			(xy 200.66 80.01) (xy 200.66 82.55)
		)
		(stroke
			(width 0)
			(type default)
		)
	)
	(wire
		(pts
			(xy 138.43 153.67) (xy 147.32 153.67)
		)
		(stroke
			(width 0)
			(type default)
		)
	)
	(wire
		(pts
			(xy 161.29 97.79) (xy 170.18 97.79)
		)
		(stroke
			(width 0)
			(type default)
		)
	)
	(bus
		(pts
			(xy 135.89 140.97) (xy 135.89 143.51)
		)
		(stroke
			(width 0)
			(type default)
		)
	)
	(wire
		(pts
			(xy 377.19 58.42) (xy 391.16 58.42)
		)
		(stroke
			(width 0)
			(type default)
		)
	)
	(bus
		(pts
			(xy 72.39 194.31) (xy 72.39 195.58)
		)
		(stroke
			(width 0)
			(type default)
		)
	)
	(wire
		(pts
			(xy 132.08 234.95) (xy 132.08 236.22)
		)
		(stroke
			(width 0)
			(type default)
		)
	)
	(wire
		(pts
			(xy 138.43 46.99) (xy 170.18 46.99)
		)
		(stroke
			(width 0)
			(type default)
		)
	)
	(wire
		(pts
			(xy 248.92 237.49) (xy 248.92 212.09)
		)
		(stroke
			(width 0)
			(type default)
		)
	)
	(wire
		(pts
			(xy 168.91 49.53) (xy 168.91 57.15)
		)
		(stroke
			(width 0)
			(type default)
		)
	)
	(wire
		(pts
			(xy 138.43 138.43) (xy 170.18 138.43)
		)
		(stroke
			(width 0)
			(type default)
		)
	)
	(wire
		(pts
			(xy 74.93 80.01) (xy 91.44 80.01)
		)
		(stroke
			(width 0)
			(type default)
		)
	)
	(wire
		(pts
			(xy 30.48 220.98) (xy 30.48 232.41)
		)
		(stroke
			(width 0)
			(type default)
		)
	)
	(wire
		(pts
			(xy 130.81 269.24) (xy 133.35 269.24)
		)
		(stroke
			(width 0)
			(type default)
		)
	)
	(bus
		(pts
			(xy 72.39 207.01) (xy 72.39 218.44)
		)
		(stroke
			(width 0)
			(type default)
		)
	)
	(wire
		(pts
			(xy 76.2 107.95) (xy 76.2 115.57)
		)
		(stroke
			(width 0)
			(type default)
		)
	)
	(wire
		(pts
			(xy 260.35 261.62) (xy 260.35 262.89)
		)
		(stroke
			(width 0)
			(type default)
		)
	)
	(wire
		(pts
			(xy 60.96 59.69) (xy 59.69 59.69)
		)
		(stroke
			(width 0)
			(type default)
		)
	)
	(bus
		(pts
			(xy 135.89 90.17) (xy 135.89 95.25)
		)
		(stroke
			(width 0)
			(type default)
		)
	)
	(wire
		(pts
			(xy 74.93 67.31) (xy 91.44 67.31)
		)
		(stroke
			(width 0)
			(type default)
		)
	)
	(wire
		(pts
			(xy 134.62 186.69) (xy 132.08 186.69)
		)
		(stroke
			(width 0)
			(type default)
		)
	)
	(polyline
		(pts
			(xy 232.41 109.22) (xy 407.67 109.22)
		)
		(stroke
			(width 0)
			(type default)
		)
	)
	(bus
		(pts
			(xy 41.91 24.13) (xy 41.91 34.29)
		)
		(stroke
			(width 0)
			(type default)
		)
	)
	(bus
		(pts
			(xy 393.7 78.74) (xy 393.7 81.28)
		)
		(stroke
			(width 0)
			(type default)
		)
	)
	(wire
		(pts
			(xy 190.5 215.9) (xy 189.23 215.9)
		)
		(stroke
			(width 0)
			(type default)
		)
	)
	(wire
		(pts
			(xy 148.59 241.3) (xy 148.59 246.38)
		)
		(stroke
			(width 0)
			(type default)
		)
	)
	(wire
		(pts
			(xy 74.93 120.65) (xy 91.44 120.65)
		)
		(stroke
			(width 0)
			(type default)
		)
	)
	(bus
		(pts
			(xy 200.66 124.46) (xy 200.66 125.73)
		)
		(stroke
			(width 0)
			(type default)
		)
	)
	(polyline
		(pts
			(xy 151.13 118.11) (xy 163.83 118.11)
		)
		(stroke
			(width 0)
			(type default)
		)
	)
	(wire
		(pts
			(xy 185.42 133.35) (xy 185.42 140.97)
		)
		(stroke
			(width 0)
			(type default)
		)
	)
	(wire
		(pts
			(xy 60.96 52.07) (xy 44.45 52.07)
		)
		(stroke
			(width 0)
			(type default)
		)
	)
	(wire
		(pts
			(xy 168.91 80.01) (xy 168.91 87.63)
		)
		(stroke
			(width 0)
			(type default)
		)
	)
	(bus
		(pts
			(xy 135.89 135.89) (xy 135.89 140.97)
		)
		(stroke
			(width 0)
			(type default)
		)
	)
	(bus
		(pts
			(xy 200.66 49.53) (xy 200.66 52.07)
		)
		(stroke
			(width 0)
			(type default)
		)
	)
	(wire
		(pts
			(xy 377.19 93.98) (xy 391.16 93.98)
		)
		(stroke
			(width 0)
			(type default)
		)
	)
	(wire
		(pts
			(xy 130.81 269.24) (xy 130.81 271.78)
		)
		(stroke
			(width 0)
			(type default)
		)
	)
	(bus
		(pts
			(xy 97.79 34.29) (xy 97.79 24.13)
		)
		(stroke
			(width 0)
			(type default)
		)
	)
	(wire
		(pts
			(xy 306.07 21.59) (xy 306.07 22.86)
		)
		(stroke
			(width 0)
			(type default)
		)
	)
	(wire
		(pts
			(xy 142.24 201.93) (xy 134.62 201.93)
		)
		(stroke
			(width 0)
			(type default)
		)
	)
	(wire
		(pts
			(xy 196.85 199.39) (xy 196.85 200.66)
		)
		(stroke
			(width 0)
			(type default)
		)
	)
	(wire
		(pts
			(xy 303.53 38.1) (xy 328.93 38.1)
		)
		(stroke
			(width 0)
			(type default)
		)
	)
	(wire
		(pts
			(xy 184.15 69.85) (xy 198.12 69.85)
		)
		(stroke
			(width 0)
			(type default)
		)
	)
	(wire
		(pts
			(xy 74.93 87.63) (xy 91.44 87.63)
		)
		(stroke
			(width 0)
			(type default)
		)
	)
	(wire
		(pts
			(xy 74.93 41.91) (xy 76.2 41.91)
		)
		(stroke
			(width 0)
			(type default)
		)
	)
	(wire
		(pts
			(xy 134.62 199.39) (xy 134.62 201.93)
		)
		(stroke
			(width 0)
			(type default)
		)
	)
	(bus
		(pts
			(xy 135.89 95.25) (xy 135.89 97.79)
		)
		(stroke
			(width 0)
			(type default)
		)
	)
	(wire
		(pts
			(xy 271.78 237.49) (xy 271.78 240.03)
		)
		(stroke
			(width 0)
			(type default)
		)
	)
	(bus
		(pts
			(xy 331.47 58.42) (xy 331.47 60.96)
		)
		(stroke
			(width 0)
			(type default)
		)
	)
	(bus
		(pts
			(xy 97.79 41.91) (xy 97.79 36.83)
		)
		(stroke
			(width 0)
			(type default)
		)
	)
	(bus
		(pts
			(xy 331.47 45.72) (xy 331.47 48.26)
		)
		(stroke
			(width 0)
			(type default)
		)
	)
	(wire
		(pts
			(xy 85.09 59.69) (xy 92.71 59.69)
		)
		(stroke
			(width 0)
			(type default)
		)
	)
	(wire
		(pts
			(xy 123.19 203.2) (xy 123.19 201.93)
		)
		(stroke
			(width 0)
			(type default)
		)
	)
	(wire
		(pts
			(xy 100.33 59.69) (xy 100.33 58.42)
		)
		(stroke
			(width 0)
			(type default)
		)
	)
	(wire
		(pts
			(xy 60.96 125.73) (xy 59.69 125.73)
		)
		(stroke
			(width 0)
			(type default)
		)
	)
	(bus
		(pts
			(xy 38.1 24.13) (xy 41.91 24.13)
		)
		(stroke
			(width 0)
			(type default)
		)
	)
	(wire
		(pts
			(xy 201.93 195.58) (xy 210.82 195.58)
		)
		(stroke
			(width 0)
			(type default)
		)
	)
	(wire
		(pts
			(xy 44.45 44.45) (xy 60.96 44.45)
		)
		(stroke
			(width 0)
			(type default)
		)
	)
	(wire
		(pts
			(xy 60.96 97.79) (xy 59.69 97.79)
		)
		(stroke
			(width 0)
			(type default)
		)
	)
	(wire
		(pts
			(xy 39.37 204.47) (xy 39.37 215.9)
		)
		(stroke
			(width 0)
			(type default)
		)
	)
	(wire
		(pts
			(xy 377.19 78.74) (xy 391.16 78.74)
		)
		(stroke
			(width 0)
			(type default)
		)
	)
	(wire
		(pts
			(xy 184.15 34.29) (xy 198.12 34.29)
		)
		(stroke
			(width 0)
			(type default)
		)
	)
	(bus
		(pts
			(xy 152.4 80.01) (xy 152.4 82.55)
		)
		(stroke
			(width 0)
			(type default)
		)
	)
	(wire
		(pts
			(xy 191.77 270.51) (xy 191.77 271.78)
		)
		(stroke
			(width 0)
			(type default)
		)
	)
	(wire
		(pts
			(xy 114.3 201.93) (xy 123.19 201.93)
		)
		(stroke
			(width 0)
			(type default)
		)
	)
	(wire
		(pts
			(xy 74.93 92.71) (xy 91.44 92.71)
		)
		(stroke
			(width 0)
			(type default)
		)
	)
	(wire
		(pts
			(xy 60.96 105.41) (xy 44.45 105.41)
		)
		(stroke
			(width 0)
			(type default)
		)
	)
	(bus
		(pts
			(xy 200.66 148.59) (xy 200.66 151.13)
		)
		(stroke
			(width 0)
			(type default)
		)
	)
	(bus
		(pts
			(xy 135.89 120.65) (xy 135.89 125.73)
		)
		(stroke
			(width 0)
			(type default)
		)
	)
	(wire
		(pts
			(xy 184.15 46.99) (xy 196.85 46.99)
		)
		(stroke
			(width 0)
			(type default)
		)
	)
	(wire
		(pts
			(xy 80.01 133.35) (xy 74.93 133.35)
		)
		(stroke
			(width 0)
			(type default)
		)
	)
	(wire
		(pts
			(xy 204.47 279.4) (xy 191.77 279.4)
		)
		(stroke
			(width 0)
			(type default)
		)
	)
	(bus
		(pts
			(xy 393.7 63.5) (xy 393.7 66.04)
		)
		(stroke
			(width 0)
			(type default)
		)
	)
	(wire
		(pts
			(xy 123.19 240.03) (xy 123.19 238.76)
		)
		(stroke
			(width 0)
			(type default)
		)
	)
	(wire
		(pts
			(xy 306.07 27.94) (xy 306.07 29.21)
		)
		(stroke
			(width 0)
			(type default)
		)
	)
	(wire
		(pts
			(xy 184.15 128.27) (xy 198.12 128.27)
		)
		(stroke
			(width 0)
			(type default)
		)
	)
	(wire
		(pts
			(xy 287.02 87.63) (xy 287.02 88.9)
		)
		(stroke
			(width 0)
			(type default)
		)
	)
	(wire
		(pts
			(xy 250.19 232.41) (xy 234.95 232.41)
		)
		(stroke
			(width 0)
			(type default)
		)
	)
	(wire
		(pts
			(xy 227.33 212.09) (xy 227.33 214.63)
		)
		(stroke
			(width 0)
			(type default)
		)
	)
	(wire
		(pts
			(xy 138.43 115.57) (xy 156.21 115.57)
		)
		(stroke
			(width 0)
			(type default)
		)
	)
	(wire
		(pts
			(xy 30.48 232.41) (xy 41.91 232.41)
		)
		(stroke
			(width 0)
			(type default)
		)
	)
	(wire
		(pts
			(xy 184.15 255.27) (xy 189.23 255.27)
		)
		(stroke
			(width 0)
			(type default)
		)
	)
	(wire
		(pts
			(xy 194.31 255.27) (xy 212.09 255.27)
		)
		(stroke
			(width 0)
			(type default)
		)
	)
	(wire
		(pts
			(xy 74.93 85.09) (xy 91.44 85.09)
		)
		(stroke
			(width 0)
			(type default)
		)
	)
	(wire
		(pts
			(xy 189.23 281.94) (xy 204.47 281.94)
		)
		(stroke
			(width 0)
			(type default)
		)
	)
	(wire
		(pts
			(xy 248.92 209.55) (xy 248.92 212.09)
		)
		(stroke
			(width 0)
			(type default)
		)
	)
	(bus
		(pts
			(xy 393.7 27.94) (xy 393.7 30.48)
		)
		(stroke
			(width 0)
			(type default)
		)
	)
	(wire
		(pts
			(xy 60.96 67.31) (xy 44.45 67.31)
		)
		(stroke
			(width 0)
			(type default)
		)
	)
	(wire
		(pts
			(xy 260.35 274.32) (xy 260.35 275.59)
		)
		(stroke
			(width 0)
			(type default)
		)
	)
	(bus
		(pts
			(xy 393.7 30.48) (xy 393.7 33.02)
		)
		(stroke
			(width 0)
			(type default)
		)
	)
	(wire
		(pts
			(xy 191.77 279.4) (xy 191.77 276.86)
		)
		(stroke
			(width 0)
			(type default)
		)
	)
	(bus
		(pts
			(xy 393.7 71.12) (xy 393.7 73.66)
		)
		(stroke
			(width 0)
			(type default)
		)
	)
	(wire
		(pts
			(xy 138.43 113.03) (xy 156.21 113.03)
		)
		(stroke
			(width 0)
			(type default)
		)
	)
	(polyline
		(pts
			(xy 236.22 106.68) (xy 262.89 106.68)
		)
		(stroke
			(width 0)
			(type default)
		)
	)
	(wire
		(pts
			(xy 184.15 41.91) (xy 185.42 41.91)
		)
		(stroke
			(width 0)
			(type default)
		)
	)
	(wire
		(pts
			(xy 74.93 115.57) (xy 76.2 115.57)
		)
		(stroke
			(width 0)
			(type default)
		)
	)
	(wire
		(pts
			(xy 123.19 201.93) (xy 134.62 201.93)
		)
		(stroke
			(width 0)
			(type default)
		)
	)
	(wire
		(pts
			(xy 254 44.45) (xy 254 48.26)
		)
		(stroke
			(width 0)
			(type default)
		)
	)
	(wire
		(pts
			(xy 168.91 118.11) (xy 168.91 125.73)
		)
		(stroke
			(width 0)
			(type default)
		)
	)
	(wire
		(pts
			(xy 185.42 102.87) (xy 185.42 110.49)
		)
		(stroke
			(width 0)
			(type default)
		)
	)
	(wire
		(pts
			(xy 138.43 130.81) (xy 170.18 130.81)
		)
		(stroke
			(width 0)
			(type default)
		)
	)
	(bus
		(pts
			(xy 331.47 38.1) (xy 331.47 40.64)
		)
		(stroke
			(width 0)
			(type default)
		)
	)
	(wire
		(pts
			(xy 59.69 85.09) (xy 59.69 97.79)
		)
		(stroke
			(width 0)
			(type default)
		)
	)
	(bus
		(pts
			(xy 105.41 165.1) (xy 104.14 165.1)
		)
		(stroke
			(width 0)
			(type default)
		)
	)
	(bus
		(pts
			(xy 393.7 53.34) (xy 393.7 55.88)
		)
		(stroke
			(width 0)
			(type default)
		)
	)
	(bus
		(pts
			(xy 393.7 38.1) (xy 393.7 40.64)
		)
		(stroke
			(width 0)
			(type default)
		)
	)
	(wire
		(pts
			(xy 74.93 158.75) (xy 90.17 158.75)
		)
		(stroke
			(width 0)
			(type default)
		)
	)
	(wire
		(pts
			(xy 168.91 41.91) (xy 168.91 49.53)
		)
		(stroke
			(width 0)
			(type default)
		)
	)
	(wire
		(pts
			(xy 68.58 198.12) (xy 69.85 198.12)
		)
		(stroke
			(width 0)
			(type default)
		)
	)
	(wire
		(pts
			(xy 250.19 167.64) (xy 236.22 167.64)
		)
		(stroke
			(width 0)
			(type default)
		)
	)
	(wire
		(pts
			(xy 377.19 30.48) (xy 391.16 30.48)
		)
		(stroke
			(width 0)
			(type default)
		)
	)
	(bus
		(pts
			(xy 266.7 36.83) (xy 266.7 38.1)
		)
		(stroke
			(width 0)
			(type default)
		)
	)
	(wire
		(pts
			(xy 60.96 151.13) (xy 44.45 151.13)
		)
		(stroke
			(width 0)
			(type default)
		)
	)
	(wire
		(pts
			(xy 266.7 195.58) (xy 266.7 196.85)
		)
		(stroke
			(width 0)
			(type default)
		)
	)
	(wire
		(pts
			(xy 134.62 186.69) (xy 134.62 187.96)
		)
		(stroke
			(width 0)
			(type default)
		)
	)
	(wire
		(pts
			(xy 74.93 151.13) (xy 90.17 151.13)
		)
		(stroke
			(width 0)
			(type default)
		)
	)
	(wire
		(pts
			(xy 377.19 63.5) (xy 391.16 63.5)
		)
		(stroke
			(width 0)
			(type default)
		)
	)
	(wire
		(pts
			(xy 247.65 66.04) (xy 278.13 66.04)
		)
		(stroke
			(width 0)
			(type default)
		)
	)
	(wire
		(pts
			(xy 303.53 48.26) (xy 328.93 48.26)
		)
		(stroke
			(width 0)
			(type default)
		)
	)
	(wire
		(pts
			(xy 168.91 64.77) (xy 168.91 72.39)
		)
		(stroke
			(width 0)
			(type default)
		)
	)
	(wire
		(pts
			(xy 184.15 115.57) (xy 196.85 115.57)
		)
		(stroke
			(width 0)
			(type default)
		)
	)
	(wire
		(pts
			(xy 138.43 123.19) (xy 170.18 123.19)
		)
		(stroke
			(width 0)
			(type default)
		)
	)
	(bus
		(pts
			(xy 200.66 128.27) (xy 200.66 133.35)
		)
		(stroke
			(width 0)
			(type default)
		)
	)
	(wire
		(pts
			(xy 377.19 83.82) (xy 391.16 83.82)
		)
		(stroke
			(width 0)
			(type default)
		)
	)
	(bus
		(pts
			(xy 393.7 25.4) (xy 393.7 27.94)
		)
		(stroke
			(width 0)
			(type default)
		)
	)
	(wire
		(pts
			(xy 157.48 158.75) (xy 170.18 158.75)
		)
		(stroke
			(width 0)
			(type default)
		)
	)
	(wire
		(pts
			(xy 184.15 74.93) (xy 198.12 74.93)
		)
		(stroke
			(width 0)
			(type default)
		)
	)
	(bus
		(pts
			(xy 393.7 58.42) (xy 393.7 60.96)
		)
		(stroke
			(width 0)
			(type default)
		)
	)
	(bus
		(pts
			(xy 201.93 124.46) (xy 200.66 124.46)
		)
		(stroke
			(width 0)
			(type default)
		)
	)
	(wire
		(pts
			(xy 138.43 92.71) (xy 156.21 92.71)
		)
		(stroke
			(width 0)
			(type default)
		)
	)
	(wire
		(pts
			(xy 280.67 271.78) (xy 266.7 271.78)
		)
		(stroke
			(width 0)
			(type default)
		)
	)
	(wire
		(pts
			(xy 275.59 76.2) (xy 278.13 76.2)
		)
		(stroke
			(width 0)
			(type default)
		)
	)
	(wire
		(pts
			(xy 60.96 49.53) (xy 59.69 49.53)
		)
		(stroke
			(width 0)
			(type default)
		)
	)
	(bus
		(pts
			(xy 393.7 68.58) (xy 393.7 71.12)
		)
		(stroke
			(width 0)
			(type default)
		)
	)
	(wire
		(pts
			(xy 95.25 125.73) (xy 86.36 125.73)
		)
		(stroke
			(width 0)
			(type default)
		)
	)
	(wire
		(pts
			(xy 44.45 204.47) (xy 39.37 204.47)
		)
		(stroke
			(width 0)
			(type default)
		)
	)
	(wire
		(pts
			(xy 377.19 91.44) (xy 391.16 91.44)
		)
		(stroke
			(width 0)
			(type default)
		)
	)
	(wire
		(pts
			(xy 248.92 212.09) (xy 250.19 212.09)
		)
		(stroke
			(width 0)
			(type default)
		)
	)
	(wire
		(pts
			(xy 138.43 34.29) (xy 170.18 34.29)
		)
		(stroke
			(width 0)
			(type default)
		)
	)
	(wire
		(pts
			(xy 255.27 195.58) (xy 255.27 196.85)
		)
		(stroke
			(width 0)
			(type default)
		)
	)
	(wire
		(pts
			(xy 255.27 76.2) (xy 255.27 74.93)
		)
		(stroke
			(width 0)
			(type default)
		)
	)
	(wire
		(pts
			(xy 44.45 254) (xy 44.45 259.08)
		)
		(stroke
			(width 0)
			(type default)
		)
	)
	(wire
		(pts
			(xy 138.43 54.61) (xy 170.18 54.61)
		)
		(stroke
			(width 0)
			(type default)
		)
	)
	(wire
		(pts
			(xy 227.33 190.5) (xy 227.33 193.04)
		)
		(stroke
			(width 0)
			(type default)
		)
	)
	(bus
		(pts
			(xy 41.91 36.83) (xy 41.91 41.91)
		)
		(stroke
			(width 0)
			(type default)
		)
	)
	(wire
		(pts
			(xy 41.91 110.49) (xy 60.96 110.49)
		)
		(stroke
			(width 0)
			(type default)
		)
	)
	(bus
		(pts
			(xy 135.89 110.49) (xy 135.89 113.03)
		)
		(stroke
			(width 0)
			(type default)
		)
	)
	(wire
		(pts
			(xy 74.93 82.55) (xy 91.44 82.55)
		)
		(stroke
			(width 0)
			(type default)
		)
	)
	(wire
		(pts
			(xy 148.59 220.98) (xy 148.59 223.52)
		)
		(stroke
			(width 0)
			(type default)
		)
	)
	(bus
		(pts
			(xy 393.7 76.2) (xy 393.7 78.74)
		)
		(stroke
			(width 0)
			(type default)
		)
	)
	(wire
		(pts
			(xy 74.93 34.29) (xy 76.2 34.29)
		)
		(stroke
			(width 0)
			(type default)
		)
	)
	(bus
		(pts
			(xy 331.47 43.18) (xy 331.47 45.72)
		)
		(stroke
			(width 0)
			(type default)
		)
	)
	(wire
		(pts
			(xy 278.13 35.56) (xy 275.59 35.56)
		)
		(stroke
			(width 0)
			(type default)
		)
	)
	(polyline
		(pts
			(xy 161.29 179.07) (xy 161.29 284.48)
		)
		(stroke
			(width 0)
			(type default)
		)
	)
	(wire
		(pts
			(xy 184.15 62.23) (xy 198.12 62.23)
		)
		(stroke
			(width 0)
			(type default)
		)
	)
	(wire
		(pts
			(xy 184.15 39.37) (xy 198.12 39.37)
		)
		(stroke
			(width 0)
			(type default)
		)
	)
	(wire
		(pts
			(xy 280.67 167.64) (xy 270.51 167.64)
		)
		(stroke
			(width 0)
			(type default)
		)
	)
	(wire
		(pts
			(xy 20.32 143.51) (xy 21.59 143.51)
		)
		(stroke
			(width 0)
			(type default)
		)
	)
	(wire
		(pts
			(xy 139.7 257.81) (xy 139.7 261.62)
		)
		(stroke
			(width 0)
			(type default)
		)
	)
	(wire
		(pts
			(xy 58.42 128.27) (xy 60.96 128.27)
		)
		(stroke
			(width 0)
			(type default)
		)
	)
	(wire
		(pts
			(xy 184.15 158.75) (xy 195.58 158.75)
		)
		(stroke
			(width 0)
			(type default)
		)
	)
	(wire
		(pts
			(xy 80.01 171.45) (xy 81.28 171.45)
		)
		(stroke
			(width 0)
			(type default)
		)
	)
	(wire
		(pts
			(xy 80.01 140.97) (xy 74.93 140.97)
		)
		(stroke
			(width 0)
			(type default)
		)
	)
	(wire
		(pts
			(xy 240.03 55.88) (xy 240.03 57.15)
		)
		(stroke
			(width 0)
			(type default)
		)
	)
	(wire
		(pts
			(xy 184.15 77.47) (xy 198.12 77.47)
		)
		(stroke
			(width 0)
			(type default)
		)
	)
	(wire
		(pts
			(xy 44.45 238.76) (xy 44.45 241.3)
		)
		(stroke
			(width 0)
			(type default)
		)
	)
	(bus
		(pts
			(xy 36.83 107.95) (xy 39.37 107.95)
		)
		(stroke
			(width 0)
			(type default)
		)
	)
	(wire
		(pts
			(xy 358.14 227.33) (xy 358.14 229.87)
		)
		(stroke
			(width 0)
			(type default)
		)
	)
	(wire
		(pts
			(xy 170.18 95.25) (xy 168.91 95.25)
		)
		(stroke
			(width 0)
			(type default)
		)
	)
	(wire
		(pts
			(xy 377.19 53.34) (xy 391.16 53.34)
		)
		(stroke
			(width 0)
			(type default)
		)
	)
	(wire
		(pts
			(xy 275.59 73.66) (xy 275.59 76.2)
		)
		(stroke
			(width 0)
			(type default)
		)
	)
	(wire
		(pts
			(xy 377.19 86.36) (xy 391.16 86.36)
		)
		(stroke
			(width 0)
			(type default)
		)
	)
	(wire
		(pts
			(xy 74.93 118.11) (xy 91.44 118.11)
		)
		(stroke
			(width 0)
			(type default)
		)
	)
	(bus
		(pts
			(xy 393.7 55.88) (xy 393.7 58.42)
		)
		(stroke
			(width 0)
			(type default)
		)
	)
	(wire
		(pts
			(xy 184.15 140.97) (xy 185.42 140.97)
		)
		(stroke
			(width 0)
			(type default)
		)
	)
	(wire
		(pts
			(xy 123.19 208.28) (xy 123.19 209.55)
		)
		(stroke
			(width 0)
			(type default)
		)
	)
	(wire
		(pts
			(xy 74.93 123.19) (xy 76.2 123.19)
		)
		(stroke
			(width 0)
			(type default)
		)
	)
	(polyline
		(pts
			(xy 12.7 179.07) (xy 232.41 179.07)
		)
		(stroke
			(width 0)
			(type default)
		)
	)
	(bus
		(pts
			(xy 135.89 57.15) (xy 135.89 59.69)
		)
		(stroke
			(width 0)
			(type default)
		)
	)
	(wire
		(pts
			(xy 60.96 82.55) (xy 44.45 82.55)
		)
		(stroke
			(width 0)
			(type default)
		)
	)
	(wire
		(pts
			(xy 134.62 236.22) (xy 134.62 238.76)
		)
		(stroke
			(width 0)
			(type default)
		)
	)
	(bus
		(pts
			(xy 135.89 59.69) (xy 135.89 87.63)
		)
		(stroke
			(width 0)
			(type default)
		)
	)
	(wire
		(pts
			(xy 184.15 87.63) (xy 198.12 87.63)
		)
		(stroke
			(width 0)
			(type default)
		)
	)
	(wire
		(pts
			(xy 170.18 102.87) (xy 168.91 102.87)
		)
		(stroke
			(width 0)
			(type default)
		)
	)
	(wire
		(pts
			(xy 170.18 49.53) (xy 168.91 49.53)
		)
		(stroke
			(width 0)
			(type default)
		)
	)
	(bus
		(pts
			(xy 152.4 74.93) (xy 152.4 80.01)
		)
		(stroke
			(width 0)
			(type default)
		)
	)
	(wire
		(pts
			(xy 130.81 276.86) (xy 130.81 278.13)
		)
		(stroke
			(width 0)
			(type default)
		)
	)
	(bus
		(pts
			(xy 331.47 35.56) (xy 331.47 38.1)
		)
		(stroke
			(width 0)
			(type default)
		)
	)
	(wire
		(pts
			(xy 74.93 156.21) (xy 80.01 156.21)
		)
		(stroke
			(width 0)
			(type default)
		)
	)
	(wire
		(pts
			(xy 303.53 45.72) (xy 328.93 45.72)
		)
		(stroke
			(width 0)
			(type default)
		)
	)
	(wire
		(pts
			(xy 306.07 34.29) (xy 306.07 43.18)
		)
		(stroke
			(width 0)
			(type default)
		)
	)
	(polyline
		(pts
			(xy 161.29 229.87) (xy 232.41 229.87)
		)
		(stroke
			(width 0)
			(type default)
		)
	)
	(wire
		(pts
			(xy 60.96 100.33) (xy 44.45 100.33)
		)
		(stroke
			(width 0)
			(type default)
		)
	)
	(polyline
		(pts
			(xy 151.13 86.36) (xy 151.13 118.11)
		)
		(stroke
			(width 0)
			(type default)
		)
	)
	(wire
		(pts
			(xy 247.65 76.2) (xy 247.65 74.93)
		)
		(stroke
			(width 0)
			(type default)
		)
	)
	(wire
		(pts
			(xy 44.45 46.99) (xy 60.96 46.99)
		)
		(stroke
			(width 0)
			(type default)
		)
	)
	(wire
		(pts
			(xy 377.19 76.2) (xy 391.16 76.2)
		)
		(stroke
			(width 0)
			(type default)
		)
	)
	(bus
		(pts
			(xy 283.21 160.02) (xy 284.48 160.02)
		)
		(stroke
			(width 0)
			(type default)
		)
	)
	(wire
		(pts
			(xy 40.64 57.15) (xy 60.96 57.15)
		)
		(stroke
			(width 0)
			(type default)
		)
	)
	(wire
		(pts
			(xy 250.19 172.72) (xy 248.92 172.72)
		)
		(stroke
			(width 0)
			(type default)
		)
	)
	(bus
		(pts
			(xy 283.21 149.86) (xy 284.48 149.86)
		)
		(stroke
			(width 0)
			(type default)
		)
	)
	(wire
		(pts
			(xy 184.15 120.65) (xy 196.85 120.65)
		)
		(stroke
			(width 0)
			(type default)
		)
	)
	(wire
		(pts
			(xy 154.94 67.31) (xy 170.18 67.31)
		)
		(stroke
			(width 0)
			(type default)
		)
	)
	(bus
		(pts
			(xy 393.7 40.64) (xy 393.7 43.18)
		)
		(stroke
			(width 0)
			(type default)
		)
	)
	(wire
		(pts
			(xy 74.93 59.69) (xy 80.01 59.69)
		)
		(stroke
			(width 0)
			(type default)
		)
	)
	(wire
		(pts
			(xy 303.53 35.56) (xy 328.93 35.56)
		)
		(stroke
			(width 0)
			(type default)
		)
	)
	(wire
		(pts
			(xy 60.96 72.39) (xy 59.69 72.39)
		)
		(stroke
			(width 0)
			(type default)
		)
	)
	(wire
		(pts
			(xy 218.44 195.58) (xy 220.98 195.58)
		)
		(stroke
			(width 0)
			(type default)
		)
	)
	(wire
		(pts
			(xy 184.15 138.43) (xy 198.12 138.43)
		)
		(stroke
			(width 0)
			(type default)
		)
	)
	(wire
		(pts
			(xy 255.27 186.69) (xy 255.27 190.5)
		)
		(stroke
			(width 0)
			(type default)
		)
	)
	(bus
		(pts
			(xy 331.47 33.02) (xy 331.47 35.56)
		)
		(stroke
			(width 0)
			(type default)
		)
	)
	(wire
		(pts
			(xy 60.96 85.09) (xy 59.69 85.09)
		)
		(stroke
			(width 0)
			(type default)
		)
	)
	(wire
		(pts
			(xy 44.45 36.83) (xy 60.96 36.83)
		)
		(stroke
			(width 0)
			(type default)
		)
	)
	(wire
		(pts
			(xy 201.93 113.03) (xy 217.17 113.03)
		)
		(stroke
			(width 0)
			(type default)
		)
	)
	(wire
		(pts
			(xy 59.69 107.95) (xy 59.69 115.57)
		)
		(stroke
			(width 0)
			(type default)
		)
	)
	(wire
		(pts
			(xy 134.62 222.25) (xy 134.62 223.52)
		)
		(stroke
			(width 0)
			(type default)
		)
	)
	(wire
		(pts
			(xy 275.59 76.2) (xy 275.59 81.28)
		)
		(stroke
			(width 0)
			(type default)
		)
	)
	(wire
		(pts
			(xy 251.46 35.56) (xy 251.46 36.83)
		)
		(stroke
			(width 0)
			(type default)
		)
	)
	(wire
		(pts
			(xy 60.96 74.93) (xy 44.45 74.93)
		)
		(stroke
			(width 0)
			(type default)
		)
	)
	(wire
		(pts
			(xy 185.42 80.01) (xy 185.42 102.87)
		)
		(stroke
			(width 0)
			(type default)
		)
	)
	(wire
		(pts
			(xy 303.53 40.64) (xy 328.93 40.64)
		)
		(stroke
			(width 0)
			(type default)
		)
	)
	(wire
		(pts
			(xy 269.24 43.18) (xy 278.13 43.18)
		)
		(stroke
			(width 0)
			(type default)
		)
	)
	(wire
		(pts
			(xy 138.43 52.07) (xy 170.18 52.07)
		)
		(stroke
			(width 0)
			(type default)
		)
	)
	(wire
		(pts
			(xy 40.64 58.42) (xy 40.64 57.15)
		)
		(stroke
			(width 0)
			(type default)
		)
	)
	(wire
		(pts
			(xy 184.15 97.79) (xy 196.85 97.79)
		)
		(stroke
			(width 0)
			(type default)
		)
	)
	(wire
		(pts
			(xy 184.15 146.05) (xy 198.12 146.05)
		)
		(stroke
			(width 0)
			(type default)
		)
	)
	(wire
		(pts
			(xy 271.78 172.72) (xy 270.51 172.72)
		)
		(stroke
			(width 0)
			(type default)
		)
	)
	(wire
		(pts
			(xy 168.91 95.25) (xy 168.91 102.87)
		)
		(stroke
			(width 0)
			(type default)
		)
	)
	(bus
		(pts
			(xy 332.74 33.02) (xy 331.47 33.02)
		)
		(stroke
			(width 0)
			(type default)
		)
	)
	(wire
		(pts
			(xy 74.93 148.59) (xy 90.17 148.59)
		)
		(stroke
			(width 0)
			(type default)
		)
	)
	(polyline
		(pts
			(xy 90.17 179.07) (xy 90.17 283.21)
		)
		(stroke
			(width 0)
			(type default)
		)
	)
	(wire
		(pts
			(xy 132.08 198.12) (xy 132.08 199.39)
		)
		(stroke
			(width 0)
			(type default)
		)
	)
	(wire
		(pts
			(xy 74.93 105.41) (xy 91.44 105.41)
		)
		(stroke
			(width 0)
			(type default)
		)
	)
	(wire
		(pts
			(xy 313.69 43.18) (xy 328.93 43.18)
		)
		(stroke
			(width 0)
			(type default)
		)
	)
	(wire
		(pts
			(xy 74.93 146.05) (xy 90.17 146.05)
		)
		(stroke
			(width 0)
			(type default)
		)
	)
	(wire
		(pts
			(xy 340.36 134.62) (xy 340.36 133.35)
		)
		(stroke
			(width 0)
			(type default)
		)
	)
	(bus
		(pts
			(xy 283.21 224.79) (xy 283.21 229.87)
		)
		(stroke
			(width 0)
			(type default)
		)
	)
	(wire
		(pts
			(xy 254 36.83) (xy 254 39.37)
		)
		(stroke
			(width 0)
			(type default)
		)
	)
	(wire
		(pts
			(xy 194.31 252.73) (xy 212.09 252.73)
		)
		(stroke
			(width 0)
			(type default)
		)
	)
	(wire
		(pts
			(xy 170.18 41.91) (xy 168.91 41.91)
		)
		(stroke
			(width 0)
			(type default)
		)
	)
	(wire
		(pts
			(xy 60.96 54.61) (xy 44.45 54.61)
		)
		(stroke
			(width 0)
			(type default)
		)
	)
	(bus
		(pts
			(xy 393.7 66.04) (xy 393.7 68.58)
		)
		(stroke
			(width 0)
			(type default)
		)
	)
	(wire
		(pts
			(xy 60.96 34.29) (xy 59.69 34.29)
		)
		(stroke
			(width 0)
			(type default)
		)
	)
	(polyline
		(pts
			(xy 90.17 215.9) (xy 161.29 215.9)
		)
		(stroke
			(width 0)
			(type default)
		)
	)
	(wire
		(pts
			(xy 21.59 143.51) (xy 25.4 143.51)
		)
		(stroke
			(width 0)
			(type default)
		)
	)
	(wire
		(pts
			(xy 271.78 212.09) (xy 271.78 210.82)
		)
		(stroke
			(width 0)
			(type default)
		)
	)
	(bus
		(pts
			(xy 283.21 214.63) (xy 284.48 214.63)
		)
		(stroke
			(width 0)
			(type default)
		)
	)
	(wire
		(pts
			(xy 157.48 151.13) (xy 170.18 151.13)
		)
		(stroke
			(width 0)
			(type default)
		)
	)
	(wire
		(pts
			(xy 377.19 22.86) (xy 391.16 22.86)
		)
		(stroke
			(width 0)
			(type default)
		)
	)
	(wire
		(pts
			(xy 74.93 77.47) (xy 91.44 77.47)
		)
		(stroke
			(width 0)
			(type default)
		)
	)
	(wire
		(pts
			(xy 134.62 185.42) (xy 134.62 186.69)
		)
		(stroke
			(width 0)
			(type default)
		)
	)
	(wire
		(pts
			(xy 168.91 222.25) (xy 168.91 223.52)
		)
		(stroke
			(width 0)
			(type default)
		)
	)
	(wire
		(pts
			(xy 76.2 123.19) (xy 76.2 163.83)
		)
		(stroke
			(width 0)
			(type default)
		)
	)
	(wire
		(pts
			(xy 184.15 82.55) (xy 198.12 82.55)
		)
		(stroke
			(width 0)
			(type default)
		)
	)
	(bus
		(pts
			(xy 200.66 67.31) (xy 200.66 72.39)
		)
		(stroke
			(width 0)
			(type default)
		)
	)
	(wire
		(pts
			(xy 80.01 168.91) (xy 80.01 171.45)
		)
		(stroke
			(width 0)
			(type default)
		)
	)
	(wire
		(pts
			(xy 76.2 41.91) (xy 76.2 49.53)
		)
		(stroke
			(width 0)
			(type default)
		)
	)
	(wire
		(pts
			(xy 185.42 110.49) (xy 185.42 118.11)
		)
		(stroke
			(width 0)
			(type default)
		)
	)
	(polyline
		(pts
			(xy 191.77 100.33) (xy 205.74 100.33)
		)
		(stroke
			(width 0)
			(type default)
		)
	)
	(wire
		(pts
			(xy 287.02 93.98) (xy 287.02 95.25)
		)
		(stroke
			(width 0)
			(type default)
		)
	)
	(bus
		(pts
			(xy 135.89 156.21) (xy 135.89 153.67)
		)
		(stroke
			(width 0)
			(type default)
		)
	)
	(wire
		(pts
			(xy 74.93 95.25) (xy 91.44 95.25)
		)
		(stroke
			(width 0)
			(type default)
		)
	)
	(wire
		(pts
			(xy 278.13 73.66) (xy 275.59 73.66)
		)
		(stroke
			(width 0)
			(type default)
		)
	)
	(wire
		(pts
			(xy 250.19 237.49) (xy 248.92 237.49)
		)
		(stroke
			(width 0)
			(type default)
		)
	)
	(wire
		(pts
			(xy 185.42 125.73) (xy 185.42 133.35)
		)
		(stroke
			(width 0)
			(type default)
		)
	)
	(wire
		(pts
			(xy 170.18 133.35) (xy 168.91 133.35)
		)
		(stroke
			(width 0)
			(type default)
		)
	)
	(wire
		(pts
			(xy 59.69 59.69) (xy 59.69 72.39)
		)
		(stroke
			(width 0)
			(type default)
		)
	)
	(wire
		(pts
			(xy 30.48 232.41) (xy 30.48 241.3)
		)
		(stroke
			(width 0)
			(type default)
		)
	)
	(bus
		(pts
			(xy 394.97 20.32) (xy 393.7 20.32)
		)
		(stroke
			(width 0)
			(type default)
		)
	)
	(wire
		(pts
			(xy 306.07 43.18) (xy 308.61 43.18)
		)
		(stroke
			(width 0)
			(type default)
		)
	)
	(wire
		(pts
			(xy 168.91 215.9) (xy 170.18 215.9)
		)
		(stroke
			(width 0)
			(type default)
		)
	)
	(wire
		(pts
			(xy 184.15 59.69) (xy 198.12 59.69)
		)
		(stroke
			(width 0)
			(type default)
		)
	)
	(wire
		(pts
			(xy 201.93 107.95) (xy 217.17 107.95)
		)
		(stroke
			(width 0)
			(type default)
		)
	)
	(wire
		(pts
			(xy 168.91 72.39) (xy 168.91 80.01)
		)
		(stroke
			(width 0)
			(type default)
		)
	)
	(wire
		(pts
			(xy 250.19 217.17) (xy 234.95 217.17)
		)
		(stroke
			(width 0)
			(type default)
		)
	)
	(bus
		(pts
			(xy 393.7 60.96) (xy 393.7 63.5)
		)
		(stroke
			(width 0)
			(type default)
		)
	)
	(wire
		(pts
			(xy 60.96 153.67) (xy 44.45 153.67)
		)
		(stroke
			(width 0)
			(type default)
		)
	)
	(wire
		(pts
			(xy 248.92 44.45) (xy 248.92 50.8)
		)
		(stroke
			(width 0)
			(type default)
		)
	)
	(wire
		(pts
			(xy 68.58 199.39) (xy 68.58 198.12)
		)
		(stroke
			(width 0)
			(type default)
		)
	)
	(wire
		(pts
			(xy 134.62 236.22) (xy 132.08 236.22)
		)
		(stroke
			(width 0)
			(type default)
		)
	)
	(wire
		(pts
			(xy 59.69 156.21) (xy 60.96 156.21)
		)
		(stroke
			(width 0)
			(type default)
		)
	)
	(bus
		(pts
			(xy 200.66 135.89) (xy 200.66 140.97)
		)
		(stroke
			(width 0)
			(type default)
		)
	)
	(wire
		(pts
			(xy 41.91 128.27) (xy 53.34 128.27)
		)
		(stroke
			(width 0)
			(type default)
		)
	)
	(bus
		(pts
			(xy 135.89 143.51) (xy 135.89 148.59)
		)
		(stroke
			(width 0)
			(type default)
		)
	)
	(wire
		(pts
			(xy 184.15 113.03) (xy 196.85 113.03)
		)
		(stroke
			(width 0)
			(type default)
		)
	)
	(bus
		(pts
			(xy 36.83 130.81) (xy 39.37 130.81)
		)
		(stroke
			(width 0)
			(type default)
		)
	)
	(wire
		(pts
			(xy 138.43 135.89) (xy 170.18 135.89)
		)
		(stroke
			(width 0)
			(type default)
		)
	)
	(wire
		(pts
			(xy 266.7 120.65) (xy 266.7 121.92)
		)
		(stroke
			(width 0)
			(type default)
		)
	)
	(wire
		(pts
			(xy 30.48 209.55) (xy 30.48 220.98)
		)
		(stroke
			(width 0)
			(type default)
		)
	)
	(wire
		(pts
			(xy 21.59 142.24) (xy 21.59 143.51)
		)
		(stroke
			(width 0)
			(type default)
		)
	)
	(wire
		(pts
			(xy 227.33 203.2) (xy 227.33 207.01)
		)
		(stroke
			(width 0)
			(type default)
		)
	)
	(wire
		(pts
			(xy 280.67 157.48) (xy 270.51 157.48)
		)
		(stroke
			(width 0)
			(type default)
		)
	)
	(wire
		(pts
			(xy 74.93 46.99) (xy 95.25 46.99)
		)
		(stroke
			(width 0)
			(type default)
		)
	)
	(wire
		(pts
			(xy 196.85 218.44) (xy 196.85 223.52)
		)
		(stroke
			(width 0)
			(type default)
		)
	)
	(wire
		(pts
			(xy 185.42 64.77) (xy 185.42 72.39)
		)
		(stroke
			(width 0)
			(type default)
		)
	)
	(wire
		(pts
			(xy 189.23 215.9) (xy 189.23 217.17)
		)
		(stroke
			(width 0)
			(type default)
		)
	)
	(wire
		(pts
			(xy 185.42 118.11) (xy 185.42 125.73)
		)
		(stroke
			(width 0)
			(type default)
		)
	)
	(bus
		(pts
			(xy 200.66 34.29) (xy 200.66 36.83)
		)
		(stroke
			(width 0)
			(type default)
		)
	)
	(wire
		(pts
			(xy 138.43 146.05) (xy 170.18 146.05)
		)
		(stroke
			(width 0)
			(type default)
		)
	)
	(wire
		(pts
			(xy 80.01 143.51) (xy 80.01 140.97)
		)
		(stroke
			(width 0)
			(type default)
		)
	)
	(bus
		(pts
			(xy 41.91 34.29) (xy 41.91 36.83)
		)
		(stroke
			(width 0)
			(type default)
		)
	)
	(wire
		(pts
			(xy 114.3 238.76) (xy 123.19 238.76)
		)
		(stroke
			(width 0)
			(type default)
		)
	)
	(wire
		(pts
			(xy 60.96 64.77) (xy 44.45 64.77)
		)
		(stroke
			(width 0)
			(type default)
		)
	)
	(wire
		(pts
			(xy 255.27 118.11) (xy 255.27 121.92)
		)
		(stroke
			(width 0)
			(type default)
		)
	)
	(wire
		(pts
			(xy 60.96 138.43) (xy 60.96 140.97)
		)
		(stroke
			(width 0)
			(type default)
		)
	)
	(wire
		(pts
			(xy 168.91 215.9) (xy 168.91 217.17)
		)
		(stroke
			(width 0)
			(type default)
		)
	)
	(wire
		(pts
			(xy 74.93 44.45) (xy 95.25 44.45)
		)
		(stroke
			(width 0)
			(type default)
		)
	)
	(wire
		(pts
			(xy 26.67 140.97) (xy 25.4 140.97)
		)
		(stroke
			(width 0)
			(type default)
		)
	)
	(wire
		(pts
			(xy 184.15 64.77) (xy 185.42 64.77)
		)
		(stroke
			(width 0)
			(type default)
		)
	)
	(wire
		(pts
			(xy 74.93 102.87) (xy 91.44 102.87)
		)
		(stroke
			(width 0)
			(type default)
		)
	)
	(wire
		(pts
			(xy 349.25 237.49) (xy 351.79 237.49)
		)
		(stroke
			(width 0)
			(type default)
		)
	)
	(wire
		(pts
			(xy 138.43 151.13) (xy 147.32 151.13)
		)
		(stroke
			(width 0)
			(type default)
		)
	)
	(bus
		(pts
			(xy 152.4 72.39) (xy 152.4 74.93)
		)
		(stroke
			(width 0)
			(type default)
		)
	)
	(wire
		(pts
			(xy 189.23 214.63) (xy 189.23 215.9)
		)
		(stroke
			(width 0)
			(type default)
		)
	)
	(wire
		(pts
			(xy 185.42 57.15) (xy 185.42 64.77)
		)
		(stroke
			(width 0)
			(type default)
		)
	)
	(wire
		(pts
			(xy 280.67 227.33) (xy 270.51 227.33)
		)
		(stroke
			(width 0)
			(type default)
		)
	)
	(wire
		(pts
			(xy 44.45 39.37) (xy 60.96 39.37)
		)
		(stroke
			(width 0)
			(type default)
		)
	)
	(wire
		(pts
			(xy 134.62 223.52) (xy 132.08 223.52)
		)
		(stroke
			(width 0)
			(type default)
		)
	)
	(wire
		(pts
			(xy 184.15 118.11) (xy 185.42 118.11)
		)
		(stroke
			(width 0)
			(type default)
		)
	)
	(wire
		(pts
			(xy 201.93 115.57) (xy 217.17 115.57)
		)
		(stroke
			(width 0)
			(type default)
		)
	)
	(wire
		(pts
			(xy 68.58 210.82) (xy 68.58 209.55)
		)
		(stroke
			(width 0)
			(type default)
		)
	)
	(wire
		(pts
			(xy 340.36 160.02) (xy 341.63 160.02)
		)
		(stroke
			(width 0)
			(type default)
		)
	)
	(wire
		(pts
			(xy 148.59 228.6) (xy 148.59 231.14)
		)
		(stroke
			(width 0)
			(type default)
		)
	)
	(bus
		(pts
			(xy 135.89 44.45) (xy 135.89 49.53)
		)
		(stroke
			(width 0)
			(type default)
		)
	)
	(wire
		(pts
			(xy 154.94 77.47) (xy 170.18 77.47)
		)
		(stroke
			(width 0)
			(type default)
		)
	)
	(wire
		(pts
			(xy 80.01 156.21) (xy 90.17 156.21)
		)
		(stroke
			(width 0)
			(type default)
		)
	)
	(wire
		(pts
			(xy 189.23 270.51) (xy 190.5 270.51)
		)
		(stroke
			(width 0)
			(type default)
		)
	)
	(wire
		(pts
			(xy 185.42 72.39) (xy 185.42 80.01)
		)
		(stroke
			(width 0)
			(type default)
		)
	)
	(wire
		(pts
			(xy 80.01 140.97) (xy 80.01 138.43)
		)
		(stroke
			(width 0)
			(type default)
		)
	)
	(polyline
		(pts
			(xy 148.59 86.36) (xy 151.13 87.63)
		)
		(stroke
			(width 0)
			(type default)
		)
	)
	(bus
		(pts
			(xy 331.47 48.26) (xy 331.47 50.8)
		)
		(stroke
			(width 0)
			(type default)
		)
	)
	(bus
		(pts
			(xy 97.79 41.91) (xy 97.79 44.45)
		)
		(stroke
			(width 0)
			(type default)
		)
	)
	(bus
		(pts
			(xy 393.7 43.18) (xy 393.7 45.72)
		)
		(stroke
			(width 0)
			(type default)
		)
	)
	(bus
		(pts
			(xy 393.7 81.28) (xy 393.7 83.82)
		)
		(stroke
			(width 0)
			(type default)
		)
	)
	(polyline
		(pts
			(xy 262.89 82.55) (xy 262.89 106.68)
		)
		(stroke
			(width 0)
			(type default)
		)
	)
	(wire
		(pts
			(xy 148.59 204.47) (xy 148.59 209.55)
		)
		(stroke
			(width 0)
			(type default)
		)
	)
	(wire
		(pts
			(xy 168.91 57.15) (xy 168.91 64.77)
		)
		(stroke
			(width 0)
			(type default)
		)
	)
	(wire
		(pts
			(xy 157.48 153.67) (xy 170.18 153.67)
		)
		(stroke
			(width 0)
			(type default)
		)
	)
	(polyline
		(pts
			(xy 163.83 118.11) (xy 163.83 86.36)
		)
		(stroke
			(width 0)
			(type default)
		)
	)
	(wire
		(pts
			(xy 184.15 123.19) (xy 196.85 123.19)
		)
		(stroke
			(width 0)
			(type default)
		)
	)
	(wire
		(pts
			(xy 184.15 54.61) (xy 198.12 54.61)
		)
		(stroke
			(width 0)
			(type default)
		)
	)
	(wire
		(pts
			(xy 185.42 49.53) (xy 185.42 57.15)
		)
		(stroke
			(width 0)
			(type default)
		)
	)
	(wire
		(pts
			(xy 185.42 140.97) (xy 185.42 148.59)
		)
		(stroke
			(width 0)
			(type default)
		)
	)
	(wire
		(pts
			(xy 74.93 36.83) (xy 95.25 36.83)
		)
		(stroke
			(width 0)
			(type default)
		)
	)
	(wire
		(pts
			(xy 184.15 85.09) (xy 198.12 85.09)
		)
		(stroke
			(width 0)
			(type default)
		)
	)
	(wire
		(pts
			(xy 185.42 148.59) (xy 185.42 156.21)
		)
		(stroke
			(width 0)
			(type default)
		)
	)
	(wire
		(pts
			(xy 39.37 241.3) (xy 44.45 241.3)
		)
		(stroke
			(width 0)
			(type default)
		)
	)
	(wire
		(pts
			(xy 74.93 113.03) (xy 91.44 113.03)
		)
		(stroke
			(width 0)
			(type default)
		)
	)
	(wire
		(pts
			(xy 138.43 158.75) (xy 147.32 158.75)
		)
		(stroke
			(width 0)
			(type default)
		)
	)
	(wire
		(pts
			(xy 31.75 241.3) (xy 30.48 241.3)
		)
		(stroke
			(width 0)
			(type default)
		)
	)
	(wire
		(pts
			(xy 138.43 107.95) (xy 156.21 107.95)
		)
		(stroke
			(width 0)
			(type default)
		)
	)
	(wire
		(pts
			(xy 184.15 133.35) (xy 185.42 133.35)
		)
		(stroke
			(width 0)
			(type default)
		)
	)
	(wire
		(pts
			(xy 74.93 125.73) (xy 81.28 125.73)
		)
		(stroke
			(width 0)
			(type default)
		)
	)
	(polyline
		(pts
			(xy 356.87 12.7) (xy 356.87 101.6)
		)
		(stroke
			(width 0)
			(type default)
		)
	)
	(polyline
		(pts
			(xy 90.17 252.73) (xy 161.29 252.73)
		)
		(stroke
			(width 0)
			(type default)
		)
	)
	(wire
		(pts
			(xy 59.69 34.29) (xy 59.69 41.91)
		)
		(stroke
			(width 0)
			(type default)
		)
	)
	(wire
		(pts
			(xy 255.27 127) (xy 255.27 128.27)
		)
		(stroke
			(width 0)
			(type default)
		)
	)
	(bus
		(pts
			(xy 97.79 36.83) (xy 97.79 34.29)
		)
		(stroke
			(width 0)
			(type default)
		)
	)
	(wire
		(pts
			(xy 254 48.26) (xy 278.13 48.26)
		)
		(stroke
			(width 0)
			(type default)
		)
	)
	(bus
		(pts
			(xy 266.7 38.1) (xy 266.7 40.64)
		)
		(stroke
			(width 0)
			(type default)
		)
	)
	(bus
		(pts
			(xy 393.7 33.02) (xy 393.7 35.56)
		)
		(stroke
			(width 0)
			(type default)
		)
	)
	(wire
		(pts
			(xy 176.53 205.74) (xy 176.53 208.28)
		)
		(stroke
			(width 0)
			(type default)
		)
	)
	(bus
		(pts
			(xy 134.62 24.13) (xy 135.89 24.13)
		)
		(stroke
			(width 0)
			(type default)
		)
	)
	(wire
		(pts
			(xy 377.19 25.4) (xy 391.16 25.4)
		)
		(stroke
			(width 0)
			(type default)
		)
	)
	(wire
		(pts
			(xy 340.36 152.4) (xy 340.36 151.13)
		)
		(stroke
			(width 0)
			(type default)
		)
	)
	(wire
		(pts
			(xy 134.62 234.95) (xy 134.62 236.22)
		)
		(stroke
			(width 0)
			(type default)
		)
	)
	(wire
		(pts
			(xy 358.14 224.79) (xy 358.14 227.33)
		)
		(stroke
			(width 0)
			(type default)
		)
	)
	(bus
		(pts
			(xy 41.91 41.91) (xy 41.91 44.45)
		)
		(stroke
			(width 0)
			(type default)
		)
	)
	(wire
		(pts
			(xy 38.1 146.05) (xy 41.91 146.05)
		)
		(stroke
			(width 0)
			(type default)
		)
	)
	(wire
		(pts
			(xy 266.7 189.23) (xy 266.7 190.5)
		)
		(stroke
			(width 0)
			(type default)
		)
	)
	(wire
		(pts
			(xy 43.18 148.59) (xy 60.96 148.59)
		)
		(stroke
			(width 0)
			(type default)
		)
	)
	(bus
		(pts
			(xy 393.7 83.82) (xy 393.7 86.36)
		)
		(stroke
			(width 0)
			(type default)
		)
	)
	(wire
		(pts
			(xy 35.56 251.46) (xy 35.56 252.73)
		)
		(stroke
			(width 0)
			(type default)
		)
	)
	(bus
		(pts
			(xy 135.89 133.35) (xy 135.89 135.89)
		)
		(stroke
			(width 0)
			(type default)
		)
	)
	(bus
		(pts
			(xy 331.47 50.8) (xy 331.47 55.88)
		)
		(stroke
			(width 0)
			(type default)
		)
	)
	(wire
		(pts
			(xy 240.03 62.23) (xy 240.03 68.58)
		)
		(stroke
			(width 0)
			(type default)
		)
	)
	(wire
		(pts
			(xy 303.53 66.04) (xy 328.93 66.04)
		)
		(stroke
			(width 0)
			(type default)
		)
	)
	(wire
		(pts
			(xy 170.18 140.97) (xy 168.91 140.97)
		)
		(stroke
			(width 0)
			(type default)
		)
	)
	(wire
		(pts
			(xy 80.01 138.43) (xy 80.01 135.89)
		)
		(stroke
			(width 0)
			(type default)
		)
	)
	(bus
		(pts
			(xy 393.7 45.72) (xy 393.7 48.26)
		)
		(stroke
			(width 0)
			(type default)
		)
	)
	(wire
		(pts
			(xy 80.01 168.91) (xy 81.28 168.91)
		)
		(stroke
			(width 0)
			(type default)
		)
	)
	(wire
		(pts
			(xy 303.53 71.12) (xy 312.42 71.12)
		)
		(stroke
			(width 0)
			(type default)
		)
	)
	(wire
		(pts
			(xy 134.62 245.11) (xy 134.62 246.38)
		)
		(stroke
			(width 0)
			(type default)
		)
	)
	(wire
		(pts
			(xy 248.92 36.83) (xy 248.92 39.37)
		)
		(stroke
			(width 0)
			(type default)
		)
	)
	(wire
		(pts
			(xy 293.37 87.63) (xy 293.37 88.9)
		)
		(stroke
			(width 0)
			(type default)
		)
	)
	(bus
		(pts
			(xy 135.89 24.13) (xy 219.71 24.13)
		)
		(stroke
			(width 0)
			(type default)
		)
	)
	(polyline
		(pts
			(xy 191.77 118.11) (xy 205.74 118.11)
		)
		(stroke
			(width 0)
			(type default)
		)
	)
	(bus
		(pts
			(xy 135.89 49.53) (xy 135.89 52.07)
		)
		(stroke
			(width 0)
			(type default)
		)
	)
	(bus
		(pts
			(xy 200.66 140.97) (xy 200.66 143.51)
		)
		(stroke
			(width 0)
			(type default)
		)
	)
	(wire
		(pts
			(xy 120.65 269.24) (xy 121.92 269.24)
		)
		(stroke
			(width 0)
			(type default)
		)
	)
	(wire
		(pts
			(xy 161.29 100.33) (xy 170.18 100.33)
		)
		(stroke
			(width 0)
			(type default)
		)
	)
	(wire
		(pts
			(xy 139.7 278.13) (xy 139.7 279.4)
		)
		(stroke
			(width 0)
			(type default)
		)
	)
	(wire
		(pts
			(xy 74.93 153.67) (xy 90.17 153.67)
		)
		(stroke
			(width 0)
			(type default)
		)
	)
	(label "HDMI.SCL"
		(at 157.48 158.75 0)
		(effects
			(font
				(size 1.27 1.27)
			)
			(justify left bottom)
		)
	)
	(label "Pf_5V.HPD"
		(at 196.85 87.63 180)
		(effects
			(font
				(size 1.27 1.27)
			)
			(justify right bottom)
		)
	)
	(label "GPIO.26"
		(at 377.19 88.9 0)
		(effects
			(font
				(size 1.27 1.27)
			)
			(justify left bottom)
		)
	)
	(label "NVMe.RX3_N"
		(at 138.43 115.57 0)
		(effects
			(font
				(size 1.27 1.27)
			)
			(justify left bottom)
		)
	)
	(label "GPIO.AIN1"
		(at 44.45 151.13 0)
		(effects
			(font
				(size 1.27 1.27)
			)
			(justify left bottom)
		)
	)
	(label "WL_nDis"
		(at 81.915 146.05 0)
		(effects
			(font
				(size 1.27 1.27)
			)
			(justify left bottom)
		)
	)
	(label "Pf_5V.SCL"
		(at 196.85 92.71 180)
		(effects
			(font
				(size 1.27 1.27)
			)
			(justify right bottom)
		)
	)
	(label "I_{2}C1.SCL"
		(at 269.24 43.18 0)
		(effects
			(font
				(size 1.27 1.27)
			)
			(justify left bottom)
		)
	)
	(label "GPIO.18"
		(at 377.19 68.58 0)
		(effects
			(font
				(size 1.27 1.27)
			)
			(justify left bottom)
		)
	)
	(label "CamCtrl.VSYNC1"
		(at 313.69 66.04 0)
		(effects
			(font
				(size 1.27 1.27)
			)
			(justify left bottom)
		)
	)
	(label "CSI0.D0_P"
		(at 154.94 69.85 0)
		(effects
			(font
				(size 1.27 1.27)
			)
			(justify left bottom)
		)
	)
	(label "NVMe.RX3_P"
		(at 138.43 113.03 0)
		(effects
			(font
				(size 1.27 1.27)
			)
			(justify left bottom)
		)
	)
	(label "CSI1.D2_N"
		(at 196.85 74.93 180)
		(effects
			(font
				(size 1.27 1.27)
			)
			(justify right bottom)
		)
	)
	(label "GPIO.19"
		(at 44.45 64.77 0)
		(effects
			(font
				(size 1.27 1.27)
			)
			(justify left bottom)
		)
	)
	(label "SDIO.D1"
		(at 91.44 118.11 180)
		(effects
			(font
				(size 1.27 1.27)
			)
			(justify right bottom)
		)
	)
	(label "GPIO.19"
		(at 377.19 71.12 0)
		(effects
			(font
				(size 1.27 1.27)
			)
			(justify left bottom)
		)
	)
	(label "NVMe.TX3_N"
		(at 217.17 113.03 180)
		(effects
			(font
				(size 1.27 1.27)
			)
			(justify right bottom)
		)
	)
	(label "T2_P"
		(at 163.83 105.41 0)
		(effects
			(font
				(size 1.27 1.27)
			)
			(justify left bottom)
		)
	)
	(label "CSI1.D0_N"
		(at 196.85 52.07 180)
		(effects
			(font
				(size 1.27 1.27)
			)
			(justify right bottom)
		)
	)
	(label "ETHERNET.D0_N"
		(at 44.45 44.45 0)
		(effects
			(font
				(size 1.27 1.27)
			)
			(justify left bottom)
		)
	)
	(label "GPIO.12/RXD5"
		(at 377.19 53.34 0)
		(effects
			(font
				(size 1.27 1.27)
			)
			(justify left bottom)
		)
	)
	(label "GPIO.23"
		(at 377.19 81.28 0)
		(effects
			(font
				(size 1.27 1.27)
			)
			(justify left bottom)
		)
	)
	(label "GPIO.0{slash}SDA0"
		(at 44.45 77.47 0)
		(effects
			(font
				(size 1.27 1.27)
			)
			(justify left bottom)
		)
	)
	(label "CamCtrl.VSYNC0"
		(at 101.6 168.91 180)
		(effects
			(font
				(size 1.27 1.27)
			)
			(justify right bottom)
		)
	)
	(label "DSICtrl.DIM"
		(at 195.58 241.3 0)
		(effects
			(font
				(size 1.27 1.27)
			)
			(justify left bottom)
		)
	)
	(label "R2_P"
		(at 186.69 107.95 0)
		(effects
			(font
				(size 1.27 1.27)
			)
			(justify left bottom)
		)
	)
	(label "CSI1.D1_P"
		(at 196.85 62.23 180)
		(effects
			(font
				(size 1.27 1.27)
			)
			(justify right bottom)
		)
	)
	(label "USB.OTGID"
		(at 95.25 266.7 0)
		(effects
			(font
				(size 1.27 1.27)
			)
			(justify left bottom)
		)
	)
	(label "USB.D_P"
		(at 196.85 39.37 180)
		(effects
			(font
				(size 1.27 1.27)
			)
			(justify right bottom)
		)
	)
	(label "ETHERNET.D2_N"
		(at 95.25 44.45 180)
		(effects
			(font
				(size 1.27 1.27)
			)
			(justify right bottom)
		)
	)
	(label "GPIO.24"
		(at 377.19 83.82 0)
		(effects
			(font
				(size 1.27 1.27)
			)
			(justify left bottom)
		)
	)
	(label "GPIO.22"
		(at 44.45 90.17 0)
		(effects
			(font
				(size 1.27 1.27)
			)
			(justify left bottom)
		)
	)
	(label "NVMe.RX0_N"
		(at 138.43 54.61 0)
		(effects
			(font
				(size 1.27 1.27)
			)
			(justify left bottom)
		)
	)
	(label "HDMI.CLK_P"
		(at 138.43 143.51 0)
		(effects
			(font
				(size 1.27 1.27)
			)
			(justify left bottom)
		)
	)
	(label "I_{2}C1.SDA"
		(at 41.91 135.89 0)
		(effects
			(font
				(size 1.27 1.27)
			)
			(justify left bottom)
		)
	)
	(label "ETHERNET.D1_N"
		(at 44.45 39.37 0)
		(effects
			(font
				(size 1.27 1.27)
			)
			(justify left bottom)
		)
	)
	(label "DSI.D2_N"
		(at 195.58 151.13 180)
		(effects
			(font
				(size 1.27 1.27)
			)
			(justify right bottom)
		)
	)
	(label "SYNC_IN"
		(at 44.45 52.07 0)
		(effects
			(font
				(size 1.27 1.27)
			)
			(justify left bottom)
		)
	)
	(label "GPIO.13{slash}TXD5"
		(at 44.45 67.31 0)
		(effects
			(font
				(size 1.27 1.27)
			)
			(justify left bottom)
		)
	)
	(label "RUN_PG"
		(at 52.07 148.59 180)
		(effects
			(font
				(size 1.27 1.27)
			)
			(justify right bottom)
		)
	)
	(label "HDMI.CEC"
		(at 196.85 97.79 180)
		(effects
			(font
				(size 1.27 1.27)
			)
			(justify right bottom)
		)
	)
	(label "UART.2.RX"
		(at 280.67 162.56 180)
		(effects
			(font
				(size 1.27 1.27)
			)
			(justify right bottom)
		)
	)
	(label "GPIO.4/TXD3"
		(at 236.22 157.48 0)
		(effects
			(font
				(size 1.27 1.27)
			)
			(justify left bottom)
		)
	)
	(label "T3_N"
		(at 186.69 113.03 0)
		(effects
			(font
				(size 1.27 1.27)
			)
			(justify left bottom)
		)
	)
	(label "CSI1.CLK_P"
		(at 196.85 69.85 180)
		(effects
			(font
				(size 1.27 1.27)
			)
			(justify right bottom)
		)
	)
	(label "GPIO.20"
		(at 91.44 67.31 180)
		(effects
			(font
				(size 1.27 1.27)
			)
			(justify right bottom)
		)
	)
	(label "RUN_PG"
		(at 148.59 246.38 0)
		(effects
			(font
				(size 1.27 1.27)
			)
			(justify left bottom)
		)
	)
	(label "CamCtrl.VSYNC0"
		(at 313.69 63.5 0)
		(effects
			(font
				(size 1.27 1.27)
			)
			(justify left bottom)
		)
	)
	(label "NVMe.~{CLK_REQ}"
		(at 138.43 34.29 0)
		(effects
			(font
				(size 1.27 1.27)
			)
			(justify left bottom)
		)
	)
	(label "ETHERNET.D0_P"
		(at 44.45 46.99 0)
		(effects
			(font
				(size 1.27 1.27)
			)
			(justify left bottom)
		)
	)
	(label "DSI.D0_N"
		(at 195.58 128.27 180)
		(effects
			(font
				(size 1.27 1.27)
			)
			(justify right bottom)
		)
	)
	(label "USB.D_N"
		(at 196.85 36.83 180)
		(effects
			(font
				(size 1.27 1.27)
			)
			(justify right bottom)
		)
	)
	(label "NVMe.CLK_P"
		(at 138.43 44.45 0)
		(effects
			(font
				(size 1.27 1.27)
			)
			(justify left bottom)
		)
	)
	(label "GPIO.8/TXD4"
		(at 236.22 167.64 0)
		(effects
			(font
				(size 1.27 1.27)
			)
			(justify left bottom)
		)
	)
	(label "UART.3.RX"
		(at 280.67 152.4 180)
		(effects
			(font
				(size 1.27 1.27)
			)
			(justify right bottom)
		)
	)
	(label "HDMI.CLK_N"
		(at 138.43 146.05 0)
		(effects
			(font
				(size 1.27 1.27)
			)
			(justify left bottom)
		)
	)
	(label "HDMI.SDA"
		(at 195.58 158.75 180)
		(effects
			(font
				(size 1.27 1.27)
			)
			(justify right bottom)
		)
	)
	(label "GPIO.1{slash}SCL0"
		(at 204.47 281.94 180)
		(effects
			(font
				(size 1.27 1.27)
			)
			(justify right bottom)
		)
	)
	(label "GPIO.21"
		(at 91.44 64.77 180)
		(effects
			(font
				(size 1.27 1.27)
			)
			(justify right bottom)
		)
	)
	(label "GPIO.20"
		(at 377.19 73.66 0)
		(effects
			(font
				(size 1.27 1.27)
			)
			(justify left bottom)
		)
	)
	(label "DSICtrl.GPIO"
		(at 313.69 58.42 0)
		(effects
			(font
				(size 1.27 1.27)
			)
			(justify left bottom)
		)
	)
	(label "HDMI.D0_P"
		(at 138.43 135.89 0)
		(effects
			(font
				(size 1.27 1.27)
			)
			(justify left bottom)
		)
	)
	(label "R1_P"
		(at 163.83 97.79 0)
		(effects
			(font
				(size 1.27 1.27)
			)
			(justify left bottom)
		)
	)
	(label "UART.2.TX"
		(at 280.67 167.64 180)
		(effects
			(font
				(size 1.27 1.27)
			)
			(justify right bottom)
		)
	)
	(label "NVMe.RX0_P"
		(at 138.43 52.07 0)
		(effects
			(font
				(size 1.27 1.27)
			)
			(justify left bottom)
		)
	)
	(label "GPIO.25"
		(at 91.44 85.09 180)
		(effects
			(font
				(size 1.27 1.27)
			)
			(justify right bottom)
		)
	)
	(label "GPIO.8{slash}TXD4"
		(at 91.44 82.55 180)
		(effects
			(font
				(size 1.27 1.27)
			)
			(justify right bottom)
		)
	)
	(label "R1_N"
		(at 163.83 100.33 0)
		(effects
			(font
				(size 1.27 1.27)
			)
			(justify left bottom)
		)
	)
	(label "PolarfireID"
		(at 30.48 251.46 180)
		(effects
			(font
				(size 1.27 1.27)
			)
			(justify right bottom)
		)
	)
	(label "HDMI.HPD"
		(at 147.32 156.21 180)
		(effects
			(font
				(size 1.27 1.27)
			)
			(justify right bottom)
		)
	)
	(label "I_{2}C1.SCL"
		(at 41.91 133.35 0)
		(effects
			(font
				(size 1.27 1.27)
			)
			(justify left bottom)
		)
	)
	(label "CSI1.D0_P"
		(at 196.85 54.61 180)
		(effects
			(font
				(size 1.27 1.27)
			)
			(justify right bottom)
		)
	)
	(label "R3_P"
		(at 163.83 113.03 0)
		(effects
			(font
				(size 1.27 1.27)
			)
			(justify left bottom)
		)
	)
	(label "ExpanderINT"
		(at 280.67 271.78 180)
		(effects
			(font
				(size 1.27 1.27)
			)
			(justify right bottom)
		)
	)
	(label "CSI1.D2_P"
		(at 196.85 77.47 180)
		(effects
			(font
				(size 1.27 1.27)
			)
			(justify right bottom)
		)
	)
	(label "GPIO.7"
		(at 377.19 40.64 0)
		(effects
			(font
				(size 1.27 1.27)
			)
			(justify left bottom)
		)
	)
	(label "PolarfireID"
		(at 344.17 237.49 180)
		(effects
			(font
				(size 1.27 1.27)
			)
			(justify right bottom)
		)
	)
	(label "I_{2}C_CSI0.SCL"
		(at 212.09 255.27 180)
		(effects
			(font
				(size 1.27 1.27)
			)
			(justify right bottom)
		)
	)
	(label "SDIO.CD"
		(at 44.45 128.27 0)
		(effects
			(font
				(size 1.27 1.27)
			)
			(justify left bottom)
		)
	)
	(label "UART.3.TX"
		(at 280.67 157.48 180)
		(effects
			(font
				(size 1.27 1.27)
			)
			(justify right bottom)
		)
	)
	(label "GPIO.8/TXD4"
		(at 377.19 43.18 0)
		(effects
			(font
				(size 1.27 1.27)
			)
			(justify left bottom)
		)
	)
	(label "DSICtrl.IRQ1"
		(at 313.69 48.26 0)
		(effects
			(font
				(size 1.27 1.27)
			)
			(justify left bottom)
		)
	)
	(label "Pf_5V.CEC"
		(at 55.88 232.41 0)
		(effects
			(font
				(size 1.27 1.27)
			)
			(justify left bottom)
		)
	)
	(label "NFC.WKUP_REQ"
		(at 313.69 43.18 0)
		(effects
			(font
				(size 1.27 1.27)
			)
			(justify left bottom)
		)
	)
	(label "GPIO.15/TXD0"
		(at 91.44 102.87 180)
		(effects
			(font
				(size 1.27 1.27)
			)
			(justify right bottom)
		)
	)
	(label "SDIO.D2"
		(at 91.44 120.65 180)
		(effects
			(font
				(size 1.27 1.27)
			)
			(justify right bottom)
		)
	)
	(label "NVMe.TX1_N"
		(at 138.43 92.71 0)
		(effects
			(font
				(size 1.27 1.27)
			)
			(justify left bottom)
		)
	)
	(label "CamCtrl.VSYNC1"
		(at 101.6 171.45 180)
		(effects
			(font
				(size 1.27 1.27)
			)
			(justify right bottom)
		)
	)
	(label "GPIO.6"
		(at 44.45 69.85 0)
		(effects
			(font
				(size 1.27 1.27)
			)
			(justify left bottom)
		)
	)
	(label "GPIO.22"
		(at 377.19 78.74 0)
		(effects
			(font
				(size 1.27 1.27)
			)
			(justify left bottom)
		)
	)
	(label "NVMe.TX0_N"
		(at 138.43 62.23 0)
		(effects
			(font
				(size 1.27 1.27)
			)
			(justify left bottom)
		)
	)
	(label "ETHERNET.LED_ACT"
		(at 95.25 52.07 180)
		(effects
			(font
				(size 1.27 1.27)
			)
			(justify right bottom)
		)
	)
	(label "GPIO.7"
		(at 91.44 80.01 180)
		(effects
			(font
				(size 1.27 1.27)
			)
			(justify right bottom)
		)
	)
	(label "CM4_3V3"
		(at 95.25 125.73 180)
		(effects
			(font
				(size 1.27 1.27)
			)
			(justify right bottom)
		)
	)
	(label "~{EEPROM_WP}"
		(at 44.45 57.15 0)
		(effects
			(font
				(size 1.27 1.27)
			)
			(justify left bottom)
		)
	)
	(label "Pf_5V.SDA"
		(at 196.85 90.17 180)
		(effects
			(font
				(size 1.27 1.27)
			)
			(justify right bottom)
		)
	)
	(label "GPIO.14/RXD0"
		(at 234.95 217.17 0)
		(effects
			(font
				(size 1.27 1.27)
			)
			(justify left bottom)
		)
	)
	(label "DSI.D1_P"
		(at 195.58 138.43 180)
		(effects
			(font
				(size 1.27 1.27)
			)
			(justify right bottom)
		)
	)
	(label "GPIO.27"
		(at 44.45 92.71 0)
		(effects
			(font
				(size 1.27 1.27)
			)
			(justify left bottom)
		)
	)
	(label "DSI.CLK_N"
		(at 195.58 143.51 180)
		(effects
			(font
				(size 1.27 1.27)
			)
			(justify right bottom)
		)
	)
	(label "USB.OTGID"
		(at 196.85 34.29 180)
		(effects
			(font
				(size 1.27 1.27)
			)
			(justify right bottom)
		)
	)
	(label "I_{2}C1.SDA"
		(at 269.24 40.64 0)
		(effects
			(font
				(size 1.27 1.27)
			)
			(justify left bottom)
		)
	)
	(label "SDIO.D0"
		(at 91.44 113.03 180)
		(effects
			(font
				(size 1.27 1.27)
			)
			(justify right bottom)
		)
	)
	(label "CM4_3V3"
		(at 33.02 140.97 0)
		(effects
			(font
				(size 1.27 1.27)
			)
			(justify left bottom)
		)
	)
	(label "SYNC_OUT"
		(at 44.45 54.61 0)
		(effects
			(font
				(size 1.27 1.27)
			)
			(justify left bottom)
		)
	)
	(label "NVMe.TX3_P"
		(at 217.17 115.57 180)
		(effects
			(font
				(size 1.27 1.27)
			)
			(justify right bottom)
		)
	)
	(label "GPIO.5/RXD3"
		(at 377.19 35.56 0)
		(effects
			(font
				(size 1.27 1.27)
			)
			(justify left bottom)
		)
	)
	(label "GPIO.10"
		(at 44.45 87.63 0)
		(effects
			(font
				(size 1.27 1.27)
			)
			(justify left bottom)
		)
	)
	(label "GPIO.9{slash}RXD4"
		(at 44.45 82.55 0)
		(effects
			(font
				(size 1.27 1.27)
			)
			(justify left bottom)
		)
	)
	(label "SDIO.D3"
		(at 91.44 110.49 180)
		(effects
			(font
				(size 1.27 1.27)
			)
			(justify right bottom)
		)
	)
	(label "DSI0_C_P"
		(at 195.58 123.19 180)
		(effects
			(font
				(size 1.27 1.27)
			)
			(justify right bottom)
		)
	)
	(label "NFC.IRQ"
		(at 313.69 38.1 0)
		(effects
			(font
				(size 1.27 1.27)
			)
			(justify left bottom)
		)
	)
	(label "T3_P"
		(at 186.69 115.57 0)
		(effects
			(font
				(size 1.27 1.27)
			)
			(justify left bottom)
		)
	)
	(label "GPIO.17"
		(at 379.73 218.44 180)
		(effects
			(font
				(size 1.27 1.27)
			)
			(justify right bottom)
		)
	)
	(label "GPIO.AIN0"
		(at 377.19 96.52 0)
		(effects
			(font
				(size 1.27 1.27)
			)
			(justify left bottom)
		)
	)
	(label "GPIO.0{slash}SDA0"
		(at 204.47 279.4 180)
		(effects
			(font
				(size 1.27 1.27)
			)
			(justify right bottom)
		)
	)
	(label "CSI1.D3_P"
		(at 196.85 85.09 180)
		(effects
			(font
				(size 1.27 1.27)
			)
			(justify right bottom)
		)
	)
	(label "GPIO.3"
		(at 44.45 102.87 0)
		(effects
			(font
				(size 1.27 1.27)
			)
			(justify left bottom)
		)
	)
	(label "ETHERNET.D2_P"
		(at 95.25 46.99 180)
		(effects
			(font
				(size 1.27 1.27)
			)
			(justify right bottom)
		)
	)
	(label "HDMI.SDA"
		(at 147.32 153.67 180)
		(effects
			(font
				(size 1.27 1.27)
			)
			(justify right bottom)
		)
	)
	(label "GPIO.18"
		(at 220.98 241.3 180)
		(effects
			(font
				(size 1.27 1.27)
			)
			(justify right bottom)
		)
	)
	(label "R3_N"
		(at 163.83 115.57 0)
		(effects
			(font
				(size 1.27 1.27)
			)
			(justify left bottom)
		)
	)
	(label "NVMe.TX2_N"
		(at 138.43 107.95 0)
		(effects
			(font
				(size 1.27 1.27)
			)
			(justify left bottom)
		)
	)
	(label "GPIO.AIN0"
		(at 44.45 153.67 0)
		(effects
			(font
				(size 1.27 1.27)
			)
			(justify left bottom)
		)
	)
	(label "DSICtrl.EN"
		(at 313.69 50.8 0)
		(effects
			(font
				(size 1.27 1.27)
			)
			(justify left bottom)
		)
	)
	(label "T2_N"
		(at 163.83 107.95 0)
		(effects
			(font
				(size 1.27 1.27)
			)
			(justify left bottom)
		)
	)
	(label "GPIO.26"
		(at 44.45 62.23 0)
		(effects
			(font
				(size 1.27 1.27)
			)
			(justify left bottom)
		)
	)
	(label "ETHERNET.D3_P"
		(at 95.25 36.83 180)
		(effects
			(font
				(size 1.27 1.27)
			)
			(justify right bottom)
		)
	)
	(label "Pf_5V.SCL"
		(at 55.88 220.98 0)
		(effects
			(font
				(size 1.27 1.27)
			)
			(justify left bottom)
		)
	)
	(label "nEXTRST"
		(at 44.45 158.75 0)
		(effects
			(font
				(size 1.27 1.27)
			)
			(justify left bottom)
		)
	)
	(label "ETHERNET.LED_LINK"
		(at 95.25 54.61 180)
		(effects
			(font
				(size 1.27 1.27)
			)
			(justify right bottom)
		)
	)
	(label "~{RPi_RST}"
		(at 148.59 220.98 0)
		(effects
			(font
				(size 1.27 1.27)
			)
			(justify left bottom)
		)
	)
	(label "GPIO.2"
		(at 377.19 27.94 0)
		(effects
			(font
				(size 1.27 1.27)
			)
			(justify left bottom)
		)
	)
	(label "GPIO.13/TXD5"
		(at 377.19 55.88 0)
		(effects
			(font
				(size 1.27 1.27)
			)
			(justify left bottom)
		)
	)
	(label "CSI1.CLK_N"
		(at 196.85 67.31 180)
		(effects
			(font
				(size 1.27 1.27)
			)
			(justify right bottom)
		)
	)
	(label "~{RPi_RST}"
		(at 89.535 158.75 180)
		(effects
			(font
				(size 1.27 1.27)
			)
			(justify right bottom)
		)
	)
	(label "NVMe.RX1_P"
		(at 138.43 97.79 0)
		(effects
			(font
				(size 1.27 1.27)
			)
			(justify left bottom)
		)
	)
	(label "HDMI.D1_P"
		(at 138.43 128.27 0)
		(effects
			(font
				(size 1.27 1.27)
			)
			(justify left bottom)
		)
	)
	(label "Pf_5V.HPD"
		(at 55.88 198.12 0)
		(effects
			(font
				(size 1.27 1.27)
			)
			(justify left bottom)
		)
	)
	(label "DSI.D1_N"
		(at 195.58 135.89 180)
		(effects
			(font
				(size 1.27 1.27)
			)
			(justify right bottom)
		)
	)
	(label "ETHERNET.D3_N"
		(at 95.25 39.37 180)
		(effects
			(font
				(size 1.27 1.27)
			)
			(justify right bottom)
		)
	)
	(label "~{PWR_LED}"
		(at 201.93 195.58 0)
		(effects
			(font
				(size 1.27 1.27)
			)
			(justify left bottom)
		)
	)
	(label "DSICtrl.~{IRQ2}"
		(at 313.69 45.72 0)
		(effects
			(font
				(size 1.27 1.27)
			)
			(justify left bottom)
		)
	)
	(label "DSI.D2_P"
		(at 195.58 153.67 180)
		(effects
			(font
				(size 1.27 1.27)
			)
			(justify right bottom)
		)
	)
	(label "GPIO.13/TXD5"
		(at 234.95 232.41 0)
		(effects
			(font
				(size 1.27 1.27)
			)
			(justify left bottom)
		)
	)
	(label "Pf_5V.SDA"
		(at 55.88 209.55 0)
		(effects
			(font
				(size 1.27 1.27)
			)
			(justify left bottom)
		)
	)
	(label "GPIO.4/TXD3"
		(at 377.19 33.02 0)
		(effects
			(font
				(size 1.27 1.27)
			)
			(justify left bottom)
		)
	)
	(label "GPIO.10"
		(at 377.19 48.26 0)
		(effects
			(font
				(size 1.27 1.27)
			)
			(justify left bottom)
		)
	)
	(label "CSI1.D3_N"
		(at 196.85 82.55 180)
		(effects
			(font
				(size 1.27 1.27)
			)
			(justify right bottom)
		)
	)
	(label "GPIO.21"
		(at 377.19 76.2 0)
		(effects
			(font
				(size 1.27 1.27)
			)
			(justify left bottom)
		)
	)
	(label "GPIO.14/RXD0"
		(at 377.19 58.42 0)
		(effects
			(font
				(size 1.27 1.27)
			)
			(justify left bottom)
		)
	)
	(label "GPIO.17"
		(at 377.19 66.04 0)
		(effects
			(font
				(size 1.27 1.27)
			)
			(justify left bottom)
		)
	)
	(label "DSI.D0_P"
		(at 195.58 130.81 180)
		(effects
			(font
				(size 1.27 1.27)
			)
			(justify right bottom)
		)
	)
	(label "DSI.D3_P"
		(at 157.48 153.67 0)
		(effects
			(font
				(size 1.27 1.27)
			)
			(justify left bottom)
		)
	)
	(label "NVMe.TX2_P"
		(at 138.43 105.41 0)
		(effects
			(font
				(size 1.27 1.27)
			)
			(justify left bottom)
		)
	)
	(label "NVMe.~{RST}"
		(at 217.17 44.45 180)
		(effects
			(font
				(size 1.27 1.27)
			)
			(justify right bottom)
		)
	)
	(label "NVMe.RX2_N"
		(at 217.17 105.41 180)
		(effects
			(font
				(size 1.27 1.27)
			)
			(justify right bottom)
		)
	)
	(label "CSI0.D1_P"
		(at 154.94 77.47 0)
		(effects
			(font
				(size 1.27 1.27)
			)
			(justify left bottom)
		)
	)
	(label "T1_P"
		(at 163.83 90.17 0)
		(effects
			(font
				(size 1.27 1.27)
			)
			(justify left bottom)
		)
	)
	(label "CSI0.CLK_P"
		(at 154.94 85.09 0)
		(effects
			(font
				(size 1.27 1.27)
			)
			(justify left bottom)
		)
	)
	(label "HDMI.HPD"
		(at 196.85 100.33 180)
		(effects
			(font
				(size 1.27 1.27)
			)
			(justify right bottom)
		)
	)
	(label "NVMe.CLK_N"
		(at 138.43 46.99 0)
		(effects
			(font
				(size 1.27 1.27)
			)
			(justify left bottom)
		)
	)
	(label "CamCtrl.EN"
		(at 313.69 60.96 0)
		(effects
			(font
				(size 1.27 1.27)
			)
			(justify left bottom)
		)
	)
	(label "GPIO.12{slash}RXD5"
		(at 91.44 72.39 180)
		(effects
			(font
				(size 1.27 1.27)
			)
			(justify right bottom)
		)
	)
	(label "~{RPi_RST}"
		(at 148.59 190.5 0)
		(effects
			(font
				(size 1.27 1.27)
			)
			(justify left bottom)
		)
	)
	(label "UART.0.TX"
		(at 280.67 222.25 180)
		(effects
			(font
				(size 1.27 1.27)
			)
			(justify right bottom)
		)
	)
	(label "GPIO.2"
		(at 44.45 105.41 0)
		(effects
			(font
				(size 1.27 1.27)
			)
			(justify left bottom)
		)
	)
	(label "GPIO.15/TXD0"
		(at 377.19 60.96 0)
		(effects
			(font
				(size 1.27 1.27)
			)
			(justify left bottom)
		)
	)
	(label "GPIO.1{slash}SCL0"
		(at 184.15 255.27 180)
		(effects
			(font
				(size 1.27 1.27)
			)
			(justify right bottom)
		)
	)
	(label "DSI0_C_N"
		(at 195.58 120.65 180)
		(effects
			(font
				(size 1.27 1.27)
			)
			(justify right bottom)
		)
	)
	(label "GPIO.16"
		(at 377.19 63.5 0)
		(effects
			(font
				(size 1.27 1.27)
			)
			(justify left bottom)
		)
	)
	(label "GPIO.4{slash}TXD3"
		(at 44.45 100.33 0)
		(effects
			(font
				(size 1.27 1.27)
			)
			(justify left bottom)
		)
	)
	(label "GPIO.5/RXD3"
		(at 236.22 152.4 0)
		(effects
			(font
				(size 1.27 1.27)
			)
			(justify left bottom)
		)
	)
	(label "SDIO.CLK"
		(at 91.44 105.41 180)
		(effects
			(font
				(size 1.27 1.27)
			)
			(justify right bottom)
		)
	)
	(label "GPIO.5{slash}RXD3"
		(at 44.45 74.93 0)
		(effects
			(font
				(size 1.27 1.27)
			)
			(justify left bottom)
		)
	)
	(label "DSICtrl.~{RST}"
		(at 313.69 53.34 0)
		(effects
			(font
				(size 1.27 1.27)
			)
			(justify left bottom)
		)
	)
	(label "GPIO.1{slash}SCL0"
		(at 377.19 25.4 0)
		(effects
			(font
				(size 1.27 1.27)
			)
			(justify left bottom)
		)
	)
	(label "UART.0.RX"
		(at 280.67 217.17 180)
		(effects
			(font
				(size 1.27 1.27)
			)
			(justify right bottom)
		)
	)
	(label "GPIO.18"
		(at 91.44 95.25 180)
		(effects
			(font
				(size 1.27 1.27)
			)
			(justify right bottom)
		)
	)
	(label "GPIO.15/TXD0"
		(at 234.95 222.25 0)
		(effects
			(font
				(size 1.27 1.27)
			)
			(justify left bottom)
		)
	)
	(label "Pf_5V.CEC"
		(at 196.85 95.25 180)
		(effects
			(font
				(size 1.27 1.27)
			)
			(justify right bottom)
		)
	)
	(label "GPIO.6"
		(at 377.19 38.1 0)
		(effects
			(font
				(size 1.27 1.27)
			)
			(justify left bottom)
		)
	)
	(label "HDMI.D2_N"
		(at 138.43 123.19 0)
		(effects
			(font
				(size 1.27 1.27)
			)
			(justify left bottom)
		)
	)
	(label "HDMI.D1_N"
		(at 138.43 130.81 0)
		(effects
			(font
				(size 1.27 1.27)
			)
			(justify left bottom)
		)
	)
	(label "GPIO.25"
		(at 377.19 86.36 0)
		(effects
			(font
				(size 1.27 1.27)
			)
			(justify left bottom)
		)
	)
	(label "GPIO.AIN1"
		(at 377.19 93.98 0)
		(effects
			(font
				(size 1.27 1.27)
			)
			(justify left bottom)
		)
	)
	(label "UART.1.TX"
		(at 280.67 232.41 180)
		(effects
			(font
				(size 1.27 1.27)
			)
			(justify right bottom)
		)
	)
	(label "~{RPi_BOOT}"
		(at 89.535 151.13 180)
		(effects
			(font
				(size 1.27 1.27)
			)
			(justify right bottom)
		)
	)
	(label "GPIO.27"
		(at 377.19 91.44 0)
		(effects
			(font
				(size 1.27 1.27)
			)
			(justify left bottom)
		)
	)
	(label "Pf_5V{HDMI}"
		(at 72.39 194.31 0)
		(effects
			(font
				(size 1.27 1.27)
			)
			(justify left bottom)
		)
	)
	(label "NFC.DWL_REQ"
		(at 313.69 40.64 0)
		(effects
			(font
				(size 1.27 1.27)
			)
			(justify left bottom)
		)
	)
	(label "Pf_5V{HDMI}"
		(at 201.93 85.09 0)
		(effects
			(font
				(size 1.27 1.27)
			)
			(justify left bottom)
		)
	)
	(label "SDIO.CD"
		(at 313.69 68.58 0)
		(effects
			(font
				(size 1.27 1.27)
			)
			(justify left bottom)
		)
	)
	(label "DSI.CLK_P"
		(at 195.58 146.05 180)
		(effects
			(font
				(size 1.27 1.27)
			)
			(justify right bottom)
		)
	)
	(label "T1_N"
		(at 163.83 92.71 0)
		(effects
			(font
				(size 1.27 1.27)
			)
			(justify left bottom)
		)
	)
	(label "SDIO.CMD"
		(at 44.45 110.49 0)
		(effects
			(font
				(size 1.27 1.27)
			)
			(justify left bottom)
		)
	)
	(label "UART.1.RX"
		(at 280.67 227.33 180)
		(effects
			(font
				(size 1.27 1.27)
			)
			(justify right bottom)
		)
	)
	(label "DSI.D3_N"
		(at 157.48 151.13 0)
		(effects
			(font
				(size 1.27 1.27)
			)
			(justify left bottom)
		)
	)
	(label "GPIO.14/RXD0"
		(at 91.44 97.79 180)
		(effects
			(font
				(size 1.27 1.27)
			)
			(justify right bottom)
		)
	)
	(label "HDMI.CEC"
		(at 147.32 158.75 180)
		(effects
			(font
				(size 1.27 1.27)
			)
			(justify right bottom)
		)
	)
	(label "ETHERNET.D1_P"
		(at 44.45 36.83 0)
		(effects
			(font
				(size 1.27 1.27)
			)
			(justify left bottom)
		)
	)
	(label "GPIO.9/RXD4"
		(at 236.22 162.56 0)
		(effects
			(font
				(size 1.27 1.27)
			)
			(justify left bottom)
		)
	)
	(label "NFC.EN"
		(at 313.69 35.56 0)
		(effects
			(font
				(size 1.27 1.27)
			)
			(justify left bottom)
		)
	)
	(label "CSI0.D0_N"
		(at 154.94 67.31 0)
		(effects
			(font
				(size 1.27 1.27)
			)
			(justify left bottom)
		)
	)
	(label "ExpanderINT"
		(at 264.16 50.8 0)
		(effects
			(font
				(size 1.27 1.27)
			)
			(justify left bottom)
		)
	)
	(label "HDMI.SCL"
		(at 147.32 151.13 180)
		(effects
			(font
				(size 1.27 1.27)
			)
			(justify right bottom)
		)
	)
	(label "I_{2}C_CSI0.SDA"
		(at 212.09 252.73 180)
		(effects
			(font
				(size 1.27 1.27)
			)
			(justify right bottom)
		)
	)
	(label "~{RPi_BOOT}"
		(at 139.7 257.81 0)
		(effects
			(font
				(size 1.27 1.27)
			)
			(justify left bottom)
		)
	)
	(label "NVMe.RX2_P"
		(at 217.17 107.95 180)
		(effects
			(font
				(size 1.27 1.27)
			)
			(justify right bottom)
		)
	)
	(label "R2_N"
		(at 186.69 105.41 0)
		(effects
			(font
				(size 1.27 1.27)
			)
			(justify left bottom)
		)
	)
	(label "GPIO.11"
		(at 44.45 80.01 0)
		(effects
			(font
				(size 1.27 1.27)
			)
			(justify left bottom)
		)
	)
	(label "CAM_GPIO"
		(at 89.535 156.21 180)
		(effects
			(font
				(size 1.27 1.27)
			)
			(justify right bottom)
		)
	)
	(label "GPIO.3"
		(at 377.19 30.48 0)
		(effects
			(font
				(size 1.27 1.27)
			)
			(justify left bottom)
		)
	)
	(label "GPIO.1{slash}SCL0"
		(at 91.44 77.47 180)
		(effects
			(font
				(size 1.27 1.27)
			)
			(justify right bottom)
		)
	)
	(label "GPIO.12/RXD5"
		(at 234.95 227.33 0)
		(effects
			(font
				(size 1.27 1.27)
			)
			(justify left bottom)
		)
	)
	(label "BT_nDis"
		(at 81.915 148.59 0)
		(effects
			(font
				(size 1.27 1.27)
			)
			(justify left bottom)
		)
	)
	(label "HDMI.D2_P"
		(at 138.43 120.65 0)
		(effects
			(font
				(size 1.27 1.27)
			)
			(justify left bottom)
		)
	)
	(label "~{PWR_LED}"
		(at 90.17 153.67 180)
		(effects
			(font
				(size 1.27 1.27)
			)
			(justify right bottom)
		)
	)
	(label "GPIO.23"
		(at 91.44 92.71 180)
		(effects
			(font
				(size 1.27 1.27)
			)
			(justify right bottom)
		)
	)
	(label "GPIO.11"
		(at 377.19 50.8 0)
		(effects
			(font
				(size 1.27 1.27)
			)
			(justify left bottom)
		)
	)
	(label "GPIO.24"
		(at 91.44 90.17 180)
		(effects
			(font
				(size 1.27 1.27)
			)
			(justify right bottom)
		)
	)
	(label "GPIO.17"
		(at 44.45 95.25 0)
		(effects
			(font
				(size 1.27 1.27)
			)
			(justify left bottom)
		)
	)
	(label "HDMI.D0_N"
		(at 138.43 138.43 0)
		(effects
			(font
				(size 1.27 1.27)
			)
			(justify left bottom)
		)
	)
	(label "CSI0.CLK_N"
		(at 154.94 82.55 0)
		(effects
			(font
				(size 1.27 1.27)
			)
			(justify left bottom)
		)
	)
	(label "GPIO.0{slash}SDA0"
		(at 184.15 252.73 180)
		(effects
			(font
				(size 1.27 1.27)
			)
			(justify right bottom)
		)
	)
	(label "CSI0.D1_N"
		(at 154.94 74.93 0)
		(effects
			(font
				(size 1.27 1.27)
			)
			(justify left bottom)
		)
	)
	(label "NVMe.TX1_P"
		(at 138.43 90.17 0)
		(effects
			(font
				(size 1.27 1.27)
			)
			(justify left bottom)
		)
	)
	(label "VDAC_COMP"
		(at 196.85 46.99 180)
		(effects
			(font
				(size 1.27 1.27)
			)
			(justify right bottom)
		)
	)
	(label "GPIO.0{slash}SDA0"
		(at 377.19 22.86 0)
		(effects
			(font
				(size 1.27 1.27)
			)
			(justify left bottom)
		)
	)
	(label "NVMe.TX0_P"
		(at 138.43 59.69 0)
		(effects
			(font
				(size 1.27 1.27)
			)
			(justify left bottom)
		)
	)
	(label "GPIO.23"
		(at 248.92 262.89 0)
		(effects
			(font
				(size 1.27 1.27)
			)
			(justify left bottom)
		)
	)
	(label "GPIO.9/RXD4"
		(at 377.19 45.72 0)
		(effects
			(font
				(size 1.27 1.27)
			)
			(justify left bottom)
		)
	)
	(label "PolarfireID"
		(at 91.44 87.63 180)
		(effects
			(font
				(size 1.27 1.27)
			)
			(justify right bottom)
		)
	)
	(label "GPIO.16"
		(at 91.44 69.85 180)
		(effects
			(font
				(size 1.27 1.27)
			)
			(justify right bottom)
		)
	)
	(label "CSI1.D1_N"
		(at 196.85 59.69 180)
		(effects
			(font
				(size 1.27 1.27)
			)
			(justify right bottom)
		)
	)
	(label "NVMe.RX1_N"
		(at 138.43 100.33 0)
		(effects
			(font
				(size 1.27 1.27)
			)
			(justify left bottom)
		)
	)
	(global_label "V_{IO}"
		(shape input)
		(at 189.23 214.63 90)
		(fields_autoplaced yes)
		(effects
			(font
				(size 1.27 1.27)
			)
			(justify left)
		)
		(property "Intersheetrefs" "${INTERSHEET_REFS}"
			(at 189.23 209.6114 90)
			(effects
				(font
					(size 1.27 1.27)
				)
				(justify left)
				(hide yes)
			)
		)
	)
	(global_label "V_{IO}"
		(shape input)
		(at 248.92 143.51 180)
		(fields_autoplaced yes)
		(effects
			(font
				(size 1.27 1.27)
			)
			(justify right)
		)
		(property "Intersheetrefs" "${INTERSHEET_REFS}"
			(at 243.959 143.4306 0)
			(effects
				(font
					(size 1.27 1.27)
				)
				(justify right)
				(hide yes)
			)
		)
	)
	(global_label "V_{IO}"
		(shape input)
		(at 248.92 209.55 180)
		(fields_autoplaced yes)
		(effects
			(font
				(size 1.27 1.27)
			)
			(justify right)
		)
		(property "Intersheetrefs" "${INTERSHEET_REFS}"
			(at 243.959 209.4706 0)
			(effects
				(font
					(size 1.27 1.27)
				)
				(justify right)
				(hide yes)
			)
		)
	)
	(global_label "V_{IO}"
		(shape output)
		(at 20.32 143.51 180)
		(fields_autoplaced yes)
		(effects
			(font
				(size 1.27 1.27)
			)
			(justify right)
		)
		(property "Intersheetrefs" "${INTERSHEET_REFS}"
			(at 15.359 143.4306 0)
			(effects
				(font
					(size 1.27 1.27)
				)
				(justify right)
				(hide yes)
			)
		)
	)
	(global_label "V_{IO}"
		(shape input)
		(at 190.5 266.7 180)
		(fields_autoplaced yes)
		(effects
			(font
				(size 1.27 1.27)
			)
			(justify right)
		)
		(property "Intersheetrefs" "${INTERSHEET_REFS}"
			(at 185.539 266.6206 0)
			(effects
				(font
					(size 1.27 1.27)
				)
				(justify right)
				(hide yes)
			)
		)
	)
	(global_label "V_{IO}"
		(shape input)
		(at 255.27 118.11 180)
		(fields_autoplaced yes)
		(effects
			(font
				(size 1.27 1.27)
			)
			(justify right)
		)
		(property "Intersheetrefs" "${INTERSHEET_REFS}"
			(at 250.309 118.0306 0)
			(effects
				(font
					(size 1.27 1.27)
				)
				(justify right)
				(hide yes)
			)
		)
	)
	(global_label "V_{IO}"
		(shape input)
		(at 58.42 130.81 180)
		(fields_autoplaced yes)
		(effects
			(font
				(size 1.27 1.27)
			)
			(justify right)
		)
		(property "Intersheetrefs" "${INTERSHEET_REFS}"
			(at 53.459 130.7306 0)
			(effects
				(font
					(size 1.27 1.27)
				)
				(justify right)
				(hide yes)
			)
		)
	)
	(global_label "V_{IO}"
		(shape input)
		(at 260.35 254 180)
		(fields_autoplaced yes)
		(effects
			(font
				(size 1.27 1.27)
			)
			(justify right)
		)
		(property "Intersheetrefs" "${INTERSHEET_REFS}"
			(at 255.389 253.9206 0)
			(effects
				(font
					(size 1.27 1.27)
				)
				(justify right)
				(hide yes)
			)
		)
	)
	(global_label "V_{IO}"
		(shape input)
		(at 255.27 186.69 180)
		(fields_autoplaced yes)
		(effects
			(font
				(size 1.27 1.27)
			)
			(justify right)
		)
		(property "Intersheetrefs" "${INTERSHEET_REFS}"
			(at 250.309 186.6106 0)
			(effects
				(font
					(size 1.27 1.27)
				)
				(justify right)
				(hide yes)
			)
		)
	)
	(hierarchical_label "SDIO{SDIO}"
		(shape bidirectional)
		(at 36.83 107.95 180)
		(effects
			(font
				(size 1.27 1.27)
			)
			(justify right)
		)
	)
	(hierarchical_label "USB{USB}"
		(shape bidirectional)
		(at 201.93 30.48 0)
		(effects
			(font
				(size 1.27 1.27)
			)
			(justify left)
		)
	)
	(hierarchical_label "CSI0{CSI}"
		(shape bidirectional)
		(at 151.13 64.77 180)
		(effects
			(font
				(size 1.27 1.27)
			)
			(justify right)
		)
	)
	(hierarchical_label "CamCtrl{CamCtrl}"
		(shape output)
		(at 332.74 58.42 0)
		(effects
			(font
				(size 1.27 1.27)
			)
			(justify left)
		)
	)
	(hierarchical_label "DSICtrl{DSICtrl}"
		(shape bidirectional)
		(at 190.5 238.76 180)
		(effects
			(font
				(size 1.27 1.27)
			)
			(justify right)
		)
	)
	(hierarchical_label "NVMe_EN"
		(shape output)
		(at 312.42 71.12 0)
		(effects
			(font
				(size 1.27 1.27)
			)
			(justify left)
		)
	)
	(hierarchical_label "CamCtrl{CamCtrl}"
		(shape output)
		(at 105.41 165.1 0)
		(effects
			(font
				(size 1.27 1.27)
			)
			(justify left)
		)
	)
	(hierarchical_label "~{POE EN}"
		(shape output)
		(at 312.42 76.2 0)
		(effects
			(font
				(size 1.27 1.27)
			)
			(justify left)
		)
	)
	(hierarchical_label "CSI1{CSI}"
		(shape bidirectional)
		(at 201.93 49.53 0)
		(effects
			(font
				(size 1.27 1.27)
			)
			(justify left)
		)
	)
	(hierarchical_label "I_{2}C_CSI0{I_{2}C}"
		(shape bidirectional)
		(at 214.63 250.19 0)
		(effects
			(font
				(size 1.27 1.27)
			)
			(justify left)
		)
	)
	(hierarchical_label "UART.1{UART}"
		(shape bidirectional)
		(at 284.48 224.79 0)
		(effects
			(font
				(size 1.27 1.27)
			)
			(justify left)
		)
	)
	(hierarchical_label "SDIO{SDIO}"
		(shape bidirectional)
		(at 332.74 66.04 0)
		(effects
			(font
				(size 1.27 1.27)
			)
			(justify left)
		)
	)
	(hierarchical_label "I_{2}C1{I_{2}C}"
		(shape bidirectional)
		(at 36.83 130.81 180)
		(effects
			(font
				(size 1.27 1.27)
			)
			(justify right)
		)
	)
	(hierarchical_label "SDIO{SDIO}"
		(shape bidirectional)
		(at 96.52 102.87 0)
		(effects
			(font
				(size 1.27 1.27)
			)
			(justify left)
		)
	)
	(hierarchical_label "DSICtrl{DSICtrl}"
		(shape bidirectional)
		(at 332.74 43.18 0)
		(effects
			(font
				(size 1.27 1.27)
			)
			(justify left)
		)
	)
	(hierarchical_label "NVMe{PCIe}"
		(shape bidirectional)
		(at 134.62 24.13 180)
		(effects
			(font
				(size 1.27 1.27)
			)
			(justify right)
		)
	)
	(hierarchical_label "ETHERNET{Ethernet}"
		(shape bidirectional)
		(at 38.1 24.13 180)
		(effects
			(font
				(size 1.27 1.27)
			)
			(justify right)
		)
	)
	(hierarchical_label "NFC{NFC}"
		(shape bidirectional)
		(at 332.74 33.02 0)
		(effects
			(font
				(size 1.27 1.27)
			)
			(justify left)
		)
	)
	(hierarchical_label "DSI{DSI}"
		(shape output)
		(at 201.93 124.46 0)
		(effects
			(font
				(size 1.27 1.27)
			)
			(justify left)
		)
	)
	(hierarchical_label "UART.0{UART}"
		(shape bidirectional)
		(at 284.48 214.63 0)
		(effects
			(font
				(size 1.27 1.27)
			)
			(justify left)
		)
	)
	(hierarchical_label "UART.3{UART}"
		(shape bidirectional)
		(at 284.48 149.86 0)
		(effects
			(font
				(size 1.27 1.27)
			)
			(justify left)
		)
	)
	(hierarchical_label "USBA_VBUS"
		(shape input)
		(at 349.25 218.44 180)
		(effects
			(font
				(size 1.27 1.27)
			)
			(justify right)
		)
	)
	(hierarchical_label "GPIO{GPIO}"
		(shape bidirectional)
		(at 394.97 20.32 0)
		(effects
			(font
				(size 1.27 1.27)
			)
			(justify left)
		)
	)
	(hierarchical_label "I_{2}C1{I_{2}C}"
		(shape bidirectional)
		(at 266.7 36.83 180)
		(effects
			(font
				(size 1.27 1.27)
			)
			(justify right)
		)
	)
	(hierarchical_label "UART.2{UART}"
		(shape bidirectional)
		(at 284.48 160.02 0)
		(effects
			(font
				(size 1.27 1.27)
			)
			(justify left)
		)
	)
	(hierarchical_label "HDMI{HDMI}"
		(shape bidirectional)
		(at 133.35 118.11 180)
		(effects
			(font
				(size 1.27 1.27)
			)
			(justify right)
		)
	)
	(symbol
		(lib_id "antmicroModules:Compute-Module-4_H1.5mm")
		(at 340.36 168.91 0)
		(unit 1)
		(exclude_from_sim no)
		(in_bom no)
		(on_board yes)
		(dnp yes)
		(fields_autoplaced yes)
		(property "Reference" "M201"
			(at 351.79 169.545 0)
			(effects
				(font
					(size 1.27 1.27)
					(thickness 0.15)
				)
				(justify left)
			)
		)
		(property "Value" "Compute-Module-4_H1.5mm"
			(at 351.79 172.085 0)
			(effects
				(font
					(size 1.27 1.27)
					(thickness 0.15)
				)
				(justify left)
			)
		)
		(property "Footprint" "antmicro-footprints:Compute-Module-4_H1.5mm"
			(at 358.14 176.53 0)
			(effects
				(font
					(size 1.27 1.27)
					(thickness 0.15)
				)
				(justify left bottom)
				(hide yes)
			)
		)
		(property "Datasheet" "https://datasheets.raspberrypi.com/cm4/cm4-datasheet.pdf"
			(at 358.14 179.07 0)
			(effects
				(font
					(size 1.27 1.27)
					(thickness 0.15)
				)
				(justify left bottom)
				(hide yes)
			)
		)
		(property "Description" ""
			(at 340.36 168.91 0)
			(effects
				(font
					(size 1.27 1.27)
				)
				(hide yes)
			)
		)
		(property "Manufacturer" "Raspberry Pi"
			(at 358.14 181.61 0)
			(effects
				(font
					(size 1.27 1.27)
					(thickness 0.15)
				)
				(justify left bottom)
				(hide yes)
			)
		)
		(property "MPN" "SC0294"
			(at 361.95 189.23 0)
			(effects
				(font
					(size 1.27 1.27)
				)
				(hide yes)
			)
		)
		(property "Author" "Antmicro"
			(at 358.14 184.15 0)
			(effects
				(font
					(size 1.27 1.27)
					(thickness 0.15)
				)
				(justify left bottom)
				(hide yes)
			)
		)
		(property "License" "Apache-2.0"
			(at 358.14 186.69 0)
			(effects
				(font
					(size 1.27 1.27)
					(thickness 0.15)
				)
				(justify left bottom)
				(hide yes)
			)
		)
		(instances
			(project "cm4-baseboard"
				(path ""
					(reference "M201")
					(unit 1)
				)
			)
		)
	)
	(symbol
		(lib_id "antmicroB2BConnectors:Socket_Hirose_DF40_2x50_DF40HC-3.0-100DS-0.4V")
		(at 74.93 34.29 0)
		(mirror y)
		(unit 1)
		(exclude_from_sim no)
		(in_bom yes)
		(on_board yes)
		(dnp no)
		(fields_autoplaced yes)
		(property "Reference" "J201"
			(at 67.945 26.67 0)
			(effects
				(font
					(size 1.27 1.27)
					(thickness 0.15)
				)
			)
		)
		(property "Value" "Socket_Hirose_DF40_2x50_DF40HC-3.0-100DS-0.4V"
			(at 76.2 27.94 0)
			(effects
				(font
					(size 1.27 1.27)
					(thickness 0.15)
				)
				(justify left bottom)
				(hide yes)
			)
		)
		(property "Footprint" "antmicro-footprints:Conn_Socket_Hirose_DF40_2x50_DF40HC-3.0-100DS-0.4V"
			(at 39.37 41.91 0)
			(effects
				(font
					(size 1.27 1.27)
					(thickness 0.15)
				)
				(justify left bottom)
				(hide yes)
			)
		)
		(property "Datasheet" "https://www.hirose.com/en/product/document?clcode=CL0684-4151-0-51&productname=DF40HC(3.0)-100DS-0.4V(51&series=DF40&documenttype=Catalog&lang=en&documentid=en_DF40_CAT"
			(at 39.37 44.45 0)
			(effects
				(font
					(size 1.27 1.27)
					(thickness 0.15)
				)
				(justify left bottom)
				(hide yes)
			)
		)
		(property "Description" ""
			(at 74.93 34.29 0)
			(effects
				(font
					(size 1.27 1.27)
				)
				(hide yes)
			)
		)
		(property "Manufacturer" "Hirose Electric"
			(at 39.37 46.99 0)
			(effects
				(font
					(size 1.27 1.27)
					(thickness 0.15)
				)
				(justify left bottom)
				(hide yes)
			)
		)
		(property "MPN" "DF40HC(3.0)-100DS-0.4V(51)"
			(at 67.945 29.21 0)
			(effects
				(font
					(size 1.27 1.27)
					(thickness 0.15)
				)
			)
		)
		(property "Author" "Antmicro"
			(at 39.37 52.07 0)
			(effects
				(font
					(size 1.27 1.27)
					(thickness 0.15)
				)
				(justify left bottom)
				(hide yes)
			)
		)
		(property "License" "Apache-2.0"
			(at 39.37 54.61 0)
			(effects
				(font
					(size 1.27 1.27)
					(thickness 0.15)
				)
				(justify left bottom)
				(hide yes)
			)
		)
		(property "Pitch" "0.4 mm"
			(at 39.37 49.53 0)
			(effects
				(font
					(size 1.27 1.27)
				)
				(justify left bottom)
				(hide yes)
			)
		)
		(pin "1"
		)
		(pin "10"
		)
		(pin "100"
		)
		(pin "11"
		)
		(pin "12"
		)
		(pin "13"
		)
		(pin "14"
		)
		(pin "15"
		)
		(pin "16"
		)
		(pin "17"
		)
		(pin "18"
		)
		(pin "19"
		)
		(pin "2"
		)
		(pin "20"
		)
		(pin "21"
		)
		(pin "22"
		)
		(pin "23"
		)
		(pin "24"
		)
		(pin "25"
		)
		(pin "26"
		)
		(pin "27"
		)
		(pin "28"
		)
		(pin "29"
		)
		(pin "3"
		)
		(pin "30"
		)
		(pin "31"
		)
		(pin "32"
		)
		(pin "33"
		)
		(pin "34"
		)
		(pin "35"
		)
		(pin "36"
		)
		(pin "37"
		)
		(pin "38"
		)
		(pin "39"
		)
		(pin "4"
		)
		(pin "40"
		)
		(pin "41"
		)
		(pin "42"
		)
		(pin "43"
		)
		(pin "44"
		)
		(pin "45"
		)
		(pin "46"
		)
		(pin "47"
		)
		(pin "48"
		)
		(pin "49"
		)
		(pin "5"
		)
		(pin "50"
		)
		(pin "51"
		)
		(pin "52"
		)
		(pin "53"
		)
		(pin "54"
		)
		(pin "55"
		)
		(pin "56"
		)
		(pin "57"
		)
		(pin "58"
		)
		(pin "59"
		)
		(pin "6"
		)
		(pin "60"
		)
		(pin "61"
		)
		(pin "62"
		)
		(pin "63"
		)
		(pin "64"
		)
		(pin "65"
		)
		(pin "66"
		)
		(pin "67"
		)
		(pin "68"
		)
		(pin "69"
		)
		(pin "7"
		)
		(pin "70"
		)
		(pin "71"
		)
		(pin "72"
		)
		(pin "73"
		)
		(pin "74"
		)
		(pin "75"
		)
		(pin "76"
		)
		(pin "77"
		)
		(pin "78"
		)
		(pin "79"
		)
		(pin "8"
		)
		(pin "80"
		)
		(pin "81"
		)
		(pin "82"
		)
		(pin "83"
		)
		(pin "84"
		)
		(pin "85"
		)
		(pin "86"
		)
		(pin "87"
		)
		(pin "88"
		)
		(pin "89"
		)
		(pin "9"
		)
		(pin "90"
		)
		(pin "91"
		)
		(pin "92"
		)
		(pin "93"
		)
		(pin "94"
		)
		(pin "95"
		)
		(pin "96"
		)
		(pin "97"
		)
		(pin "98"
		)
		(pin "99"
		)
		(instances
			(project "cm4-baseboard"
				(path ""
					(reference "J201")
					(unit 1)
				)
			)
		)
	)
	(symbol
		(lib_id "antmicroB2BConnectors:Socket_Hirose_DF40_2x50_DF40HC-3.0-100DS-0.4V")
		(at 184.15 34.29 0)
		(mirror y)
		(unit 1)
		(exclude_from_sim no)
		(in_bom yes)
		(on_board yes)
		(dnp no)
		(fields_autoplaced yes)
		(property "Reference" "J202"
			(at 177.165 26.67 0)
			(effects
				(font
					(size 1.27 1.27)
					(thickness 0.15)
				)
			)
		)
		(property "Value" "Socket_Hirose_DF40_2x50_DF40HC-3.0-100DS-0.4V"
			(at 185.42 27.94 0)
			(effects
				(font
					(size 1.27 1.27)
					(thickness 0.15)
				)
				(justify left bottom)
				(hide yes)
			)
		)
		(property "Footprint" "antmicro-footprints:Conn_Socket_Hirose_DF40_2x50_DF40HC-3.0-100DS-0.4V"
			(at 148.59 41.91 0)
			(effects
				(font
					(size 1.27 1.27)
					(thickness 0.15)
				)
				(justify left bottom)
				(hide yes)
			)
		)
		(property "Datasheet" "https://www.hirose.com/en/product/document?clcode=CL0684-4151-0-51&productname=DF40HC(3.0)-100DS-0.4V(51&series=DF40&documenttype=Catalog&lang=en&documentid=en_DF40_CAT"
			(at 148.59 44.45 0)
			(effects
				(font
					(size 1.27 1.27)
					(thickness 0.15)
				)
				(justify left bottom)
				(hide yes)
			)
		)
		(property "Description" ""
			(at 184.15 34.29 0)
			(effects
				(font
					(size 1.27 1.27)
				)
				(hide yes)
			)
		)
		(property "Manufacturer" "Hirose Electric"
			(at 148.59 46.99 0)
			(effects
				(font
					(size 1.27 1.27)
					(thickness 0.15)
				)
				(justify left bottom)
				(hide yes)
			)
		)
		(property "MPN" "DF40HC(3.0)-100DS-0.4V(51)"
			(at 177.165 29.21 0)
			(effects
				(font
					(size 1.27 1.27)
					(thickness 0.15)
				)
			)
		)
		(property "Author" "Antmicro"
			(at 148.59 52.07 0)
			(effects
				(font
					(size 1.27 1.27)
					(thickness 0.15)
				)
				(justify left bottom)
				(hide yes)
			)
		)
		(property "License" "Apache-2.0"
			(at 148.59 54.61 0)
			(effects
				(font
					(size 1.27 1.27)
					(thickness 0.15)
				)
				(justify left bottom)
				(hide yes)
			)
		)
		(property "Pitch" "0.4 mm"
			(at 148.59 49.53 0)
			(effects
				(font
					(size 1.27 1.27)
				)
				(justify left bottom)
				(hide yes)
			)
		)
		(pin "1"
		)
		(pin "10"
		)
		(pin "100"
		)
		(pin "11"
		)
		(pin "12"
		)
		(pin "13"
		)
		(pin "14"
		)
		(pin "15"
		)
		(pin "16"
		)
		(pin "17"
		)
		(pin "18"
		)
		(pin "19"
		)
		(pin "2"
		)
		(pin "20"
		)
		(pin "21"
		)
		(pin "22"
		)
		(pin "23"
		)
		(pin "24"
		)
		(pin "25"
		)
		(pin "26"
		)
		(pin "27"
		)
		(pin "28"
		)
		(pin "29"
		)
		(pin "3"
		)
		(pin "30"
		)
		(pin "31"
		)
		(pin "32"
		)
		(pin "33"
		)
		(pin "34"
		)
		(pin "35"
		)
		(pin "36"
		)
		(pin "37"
		)
		(pin "38"
		)
		(pin "39"
		)
		(pin "4"
		)
		(pin "40"
		)
		(pin "41"
		)
		(pin "42"
		)
		(pin "43"
		)
		(pin "44"
		)
		(pin "45"
		)
		(pin "46"
		)
		(pin "47"
		)
		(pin "48"
		)
		(pin "49"
		)
		(pin "5"
		)
		(pin "50"
		)
		(pin "51"
		)
		(pin "52"
		)
		(pin "53"
		)
		(pin "54"
		)
		(pin "55"
		)
		(pin "56"
		)
		(pin "57"
		)
		(pin "58"
		)
		(pin "59"
		)
		(pin "6"
		)
		(pin "60"
		)
		(pin "61"
		)
		(pin "62"
		)
		(pin "63"
		)
		(pin "64"
		)
		(pin "65"
		)
		(pin "66"
		)
		(pin "67"
		)
		(pin "68"
		)
		(pin "69"
		)
		(pin "7"
		)
		(pin "70"
		)
		(pin "71"
		)
		(pin "72"
		)
		(pin "73"
		)
		(pin "74"
		)
		(pin "75"
		)
		(pin "76"
		)
		(pin "77"
		)
		(pin "78"
		)
		(pin "79"
		)
		(pin "8"
		)
		(pin "80"
		)
		(pin "81"
		)
		(pin "82"
		)
		(pin "83"
		)
		(pin "84"
		)
		(pin "85"
		)
		(pin "86"
		)
		(pin "87"
		)
		(pin "88"
		)
		(pin "89"
		)
		(pin "9"
		)
		(pin "90"
		)
		(pin "91"
		)
		(pin "92"
		)
		(pin "93"
		)
		(pin "94"
		)
		(pin "95"
		)
		(pin "96"
		)
		(pin "97"
		)
		(pin "98"
		)
		(pin "99"
		)
		(instances
			(project "cm4-baseboard"
				(path ""
					(reference "J202")
					(unit 1)
				)
			)
		)
	)
	(symbol
		(lib_id "antmicroMechanicalParts:Spacer_Drill3.7mm_H3mm_9774030151R")
		(at 341.63 133.35 0)
		(unit 1)
		(exclude_from_sim no)
		(in_bom yes)
		(on_board yes)
		(dnp no)
		(fields_autoplaced yes)
		(property "Reference" "H201"
			(at 350.52 132.0799 0)
			(effects
				(font
					(size 1.27 1.27)
					(thickness 0.15)
				)
				(justify left)
			)
		)
		(property "Value" "Spacer_Drill3.7mm_H3mm_9774030151R"
			(at 350.52 134.6199 0)
			(effects
				(font
					(size 1.27 1.27)
					(thickness 0.15)
				)
				(justify left)
			)
		)
		(property "Footprint" "antmicro-footprints:Spacer_Drill3.7mm_H3mm_9774030151R"
			(at 364.49 140.97 0)
			(effects
				(font
					(size 1.27 1.27)
					(thickness 0.15)
				)
				(justify left bottom)
				(hide yes)
			)
		)
		(property "Datasheet" "https://www.we-online.com/catalog/datasheet/9774030151.pdf"
			(at 364.49 143.51 0)
			(effects
				(font
					(size 1.27 1.27)
					(thickness 0.15)
				)
				(justify left bottom)
				(hide yes)
			)
		)
		(property "Description" ""
			(at 341.63 133.35 0)
			(effects
				(font
					(size 1.27 1.27)
				)
				(hide yes)
			)
		)
		(property "Manufacturer" "Würth Elektronik"
			(at 364.49 146.05 0)
			(effects
				(font
					(size 1.27 1.27)
					(thickness 0.15)
				)
				(justify left bottom)
				(hide yes)
			)
		)
		(property "MPN" "9774030151R"
			(at 364.49 148.59 0)
			(effects
				(font
					(size 1.27 1.27)
					(thickness 0.15)
				)
				(justify left bottom)
				(hide yes)
			)
		)
		(property "Author" "Antmicro"
			(at 364.49 151.13 0)
			(effects
				(font
					(size 1.27 1.27)
					(thickness 0.15)
				)
				(justify left bottom)
				(hide yes)
			)
		)
		(property "License" "Apache-2.0"
			(at 364.49 153.67 0)
			(effects
				(font
					(size 1.27 1.27)
					(thickness 0.15)
				)
				(justify left bottom)
				(hide yes)
			)
		)
		(pin "1"
		)
		(instances
			(project "cm4-baseboard"
				(path ""
					(reference "H201")
					(unit 1)
				)
			)
		)
	)
	(symbol
		(lib_id "antmicroMechanicalParts:Spacer_Drill3.7mm_H3mm_9774030151R")
		(at 341.63 142.24 0)
		(unit 1)
		(exclude_from_sim no)
		(in_bom yes)
		(on_board yes)
		(dnp no)
		(fields_autoplaced yes)
		(property "Reference" "H202"
			(at 350.52 140.9699 0)
			(effects
				(font
					(size 1.27 1.27)
					(thickness 0.15)
				)
				(justify left)
			)
		)
		(property "Value" "Spacer_Drill3.7mm_H3mm_9774030151R"
			(at 350.52 143.5099 0)
			(effects
				(font
					(size 1.27 1.27)
					(thickness 0.15)
				)
				(justify left)
			)
		)
		(property "Footprint" "antmicro-footprints:Spacer_Drill3.7mm_H3mm_9774030151R"
			(at 364.49 149.86 0)
			(effects
				(font
					(size 1.27 1.27)
					(thickness 0.15)
				)
				(justify left bottom)
				(hide yes)
			)
		)
		(property "Datasheet" "https://www.we-online.com/catalog/datasheet/9774030151.pdf"
			(at 364.49 152.4 0)
			(effects
				(font
					(size 1.27 1.27)
					(thickness 0.15)
				)
				(justify left bottom)
				(hide yes)
			)
		)
		(property "Description" ""
			(at 341.63 142.24 0)
			(effects
				(font
					(size 1.27 1.27)
				)
				(hide yes)
			)
		)
		(property "Manufacturer" "Würth Elektronik"
			(at 364.49 154.94 0)
			(effects
				(font
					(size 1.27 1.27)
					(thickness 0.15)
				)
				(justify left bottom)
				(hide yes)
			)
		)
		(property "MPN" "9774030151R"
			(at 364.49 157.48 0)
			(effects
				(font
					(size 1.27 1.27)
					(thickness 0.15)
				)
				(justify left bottom)
				(hide yes)
			)
		)
		(property "Author" "Antmicro"
			(at 364.49 160.02 0)
			(effects
				(font
					(size 1.27 1.27)
					(thickness 0.15)
				)
				(justify left bottom)
				(hide yes)
			)
		)
		(property "License" "Apache-2.0"
			(at 364.49 162.56 0)
			(effects
				(font
					(size 1.27 1.27)
					(thickness 0.15)
				)
				(justify left bottom)
				(hide yes)
			)
		)
		(pin "1"
		)
		(instances
			(project "cm4-baseboard"
				(path ""
					(reference "H202")
					(unit 1)
				)
			)
		)
	)
	(symbol
		(lib_id "antmicroMechanicalParts:Spacer_Drill3.7mm_H3mm_9774030151R")
		(at 341.63 151.13 0)
		(unit 1)
		(exclude_from_sim no)
		(in_bom yes)
		(on_board yes)
		(dnp no)
		(fields_autoplaced yes)
		(property "Reference" "H203"
			(at 350.52 149.8599 0)
			(effects
				(font
					(size 1.27 1.27)
					(thickness 0.15)
				)
				(justify left)
			)
		)
		(property "Value" "Spacer_Drill3.7mm_H3mm_9774030151R"
			(at 350.52 152.3999 0)
			(effects
				(font
					(size 1.27 1.27)
					(thickness 0.15)
				)
				(justify left)
			)
		)
		(property "Footprint" "antmicro-footprints:Spacer_Drill3.7mm_H3mm_9774030151R"
			(at 364.49 158.75 0)
			(effects
				(font
					(size 1.27 1.27)
					(thickness 0.15)
				)
				(justify left bottom)
				(hide yes)
			)
		)
		(property "Datasheet" "https://www.we-online.com/catalog/datasheet/9774030151.pdf"
			(at 364.49 161.29 0)
			(effects
				(font
					(size 1.27 1.27)
					(thickness 0.15)
				)
				(justify left bottom)
				(hide yes)
			)
		)
		(property "Description" ""
			(at 341.63 151.13 0)
			(effects
				(font
					(size 1.27 1.27)
				)
				(hide yes)
			)
		)
		(property "Manufacturer" "Würth Elektronik"
			(at 364.49 163.83 0)
			(effects
				(font
					(size 1.27 1.27)
					(thickness 0.15)
				)
				(justify left bottom)
				(hide yes)
			)
		)
		(property "MPN" "9774030151R"
			(at 364.49 166.37 0)
			(effects
				(font
					(size 1.27 1.27)
					(thickness 0.15)
				)
				(justify left bottom)
				(hide yes)
			)
		)
		(property "Author" "Antmicro"
			(at 364.49 168.91 0)
			(effects
				(font
					(size 1.27 1.27)
					(thickness 0.15)
				)
				(justify left bottom)
				(hide yes)
			)
		)
		(property "License" "Apache-2.0"
			(at 364.49 171.45 0)
			(effects
				(font
					(size 1.27 1.27)
					(thickness 0.15)
				)
				(justify left bottom)
				(hide yes)
			)
		)
		(pin "1"
		)
		(instances
			(project "cm4-baseboard"
				(path ""
					(reference "H203")
					(unit 1)
				)
			)
		)
	)
	(symbol
		(lib_id "antmicroMechanicalParts:Spacer_Drill3.7mm_H3mm_9774030151R")
		(at 341.63 160.02 0)
		(unit 1)
		(exclude_from_sim no)
		(in_bom yes)
		(on_board yes)
		(dnp no)
		(fields_autoplaced yes)
		(property "Reference" "H204"
			(at 350.52 158.7499 0)
			(effects
				(font
					(size 1.27 1.27)
					(thickness 0.15)
				)
				(justify left)
			)
		)
		(property "Value" "Spacer_Drill3.7mm_H3mm_9774030151R"
			(at 350.52 161.2899 0)
			(effects
				(font
					(size 1.27 1.27)
					(thickness 0.15)
				)
				(justify left)
			)
		)
		(property "Footprint" "antmicro-footprints:Spacer_Drill3.7mm_H3mm_9774030151R"
			(at 364.49 167.64 0)
			(effects
				(font
					(size 1.27 1.27)
					(thickness 0.15)
				)
				(justify left bottom)
				(hide yes)
			)
		)
		(property "Datasheet" "https://www.we-online.com/catalog/datasheet/9774030151.pdf"
			(at 364.49 170.18 0)
			(effects
				(font
					(size 1.27 1.27)
					(thickness 0.15)
				)
				(justify left bottom)
				(hide yes)
			)
		)
		(property "Description" ""
			(at 341.63 160.02 0)
			(effects
				(font
					(size 1.27 1.27)
				)
				(hide yes)
			)
		)
		(property "Manufacturer" "Würth Elektronik"
			(at 364.49 172.72 0)
			(effects
				(font
					(size 1.27 1.27)
					(thickness 0.15)
				)
				(justify left bottom)
				(hide yes)
			)
		)
		(property "MPN" "9774030151R"
			(at 364.49 175.26 0)
			(effects
				(font
					(size 1.27 1.27)
					(thickness 0.15)
				)
				(justify left bottom)
				(hide yes)
			)
		)
		(property "Author" "Antmicro"
			(at 364.49 177.8 0)
			(effects
				(font
					(size 1.27 1.27)
					(thickness 0.15)
				)
				(justify left bottom)
				(hide yes)
			)
		)
		(property "License" "Apache-2.0"
			(at 364.49 180.34 0)
			(effects
				(font
					(size 1.27 1.27)
					(thickness 0.15)
				)
				(justify left bottom)
				(hide yes)
			)
		)
		(pin "1"
		)
		(instances
			(project "cm4-baseboard"
				(path ""
					(reference "H204")
					(unit 1)
				)
			)
		)
	)
	(symbol
		(lib_id "antmicropower:GND")
		(at 76.2 163.83 0)
		(unit 1)
		(exclude_from_sim no)
		(in_bom yes)
		(on_board yes)
		(dnp no)
		(fields_autoplaced yes)
		(property "Reference" "#PWR0207"
			(at 85.09 166.37 0)
			(effects
				(font
					(size 1.27 1.27)
					(thickness 0.15)
				)
				(justify left bottom)
				(hide yes)
			)
		)
		(property "Value" "GND"
			(at 74.1898 168.91 0)
			(effects
				(font
					(size 1.27 1.27)
					(thickness 0.15)
				)
				(justify left bottom)
			)
		)
		(property "Footprint" ""
			(at 85.09 171.45 0)
			(effects
				(font
					(size 1.27 1.27)
					(thickness 0.15)
				)
				(justify left bottom)
				(hide yes)
			)
		)
		(property "Datasheet" ""
			(at 85.09 176.53 0)
			(effects
				(font
					(size 1.27 1.27)
					(thickness 0.15)
				)
				(justify left bottom)
				(hide yes)
			)
		)
		(property "Description" ""
			(at 76.2 163.83 0)
			(effects
				(font
					(size 1.27 1.27)
				)
				(hide yes)
			)
		)
		(property "Author" "Antmicro"
			(at 85.09 171.45 0)
			(effects
				(font
					(size 1.27 1.27)
					(thickness 0.15)
				)
				(justify left bottom)
				(hide yes)
			)
		)
		(property "License" "Apache-2.0"
			(at 85.09 173.99 0)
			(effects
				(font
					(size 1.27 1.27)
					(thickness 0.15)
				)
				(justify left bottom)
				(hide yes)
			)
		)
		(pin "1"
		)
		(instances
			(project "cm4-baseboard"
				(path ""
					(reference "#PWR0207")
					(unit 1)
				)
			)
		)
	)
	(symbol
		(lib_id "antmicropower:GND")
		(at 59.69 163.83 0)
		(unit 1)
		(exclude_from_sim no)
		(in_bom yes)
		(on_board yes)
		(dnp no)
		(fields_autoplaced yes)
		(property "Reference" "#PWR0206"
			(at 68.58 166.37 0)
			(effects
				(font
					(size 1.27 1.27)
					(thickness 0.15)
				)
				(justify left bottom)
				(hide yes)
			)
		)
		(property "Value" "GND"
			(at 57.6798 168.91 0)
			(effects
				(font
					(size 1.27 1.27)
					(thickness 0.15)
				)
				(justify left bottom)
			)
		)
		(property "Footprint" ""
			(at 68.58 171.45 0)
			(effects
				(font
					(size 1.27 1.27)
					(thickness 0.15)
				)
				(justify left bottom)
				(hide yes)
			)
		)
		(property "Datasheet" ""
			(at 68.58 176.53 0)
			(effects
				(font
					(size 1.27 1.27)
					(thickness 0.15)
				)
				(justify left bottom)
				(hide yes)
			)
		)
		(property "Description" ""
			(at 59.69 163.83 0)
			(effects
				(font
					(size 1.27 1.27)
				)
				(hide yes)
			)
		)
		(property "Author" "Antmicro"
			(at 68.58 171.45 0)
			(effects
				(font
					(size 1.27 1.27)
					(thickness 0.15)
				)
				(justify left bottom)
				(hide yes)
			)
		)
		(property "License" "Apache-2.0"
			(at 68.58 173.99 0)
			(effects
				(font
					(size 1.27 1.27)
					(thickness 0.15)
				)
				(justify left bottom)
				(hide yes)
			)
		)
		(pin "1"
		)
		(instances
			(project "cm4-baseboard"
				(path ""
					(reference "#PWR0206")
					(unit 1)
				)
			)
		)
	)
	(symbol
		(lib_id "antmicropower:GND")
		(at 168.91 165.1 0)
		(unit 1)
		(exclude_from_sim no)
		(in_bom yes)
		(on_board yes)
		(dnp no)
		(fields_autoplaced yes)
		(property "Reference" "#PWR0222"
			(at 177.8 167.64 0)
			(effects
				(font
					(size 1.27 1.27)
					(thickness 0.15)
				)
				(justify left bottom)
				(hide yes)
			)
		)
		(property "Value" "GND"
			(at 166.8998 170.18 0)
			(effects
				(font
					(size 1.27 1.27)
					(thickness 0.15)
				)
				(justify left bottom)
			)
		)
		(property "Footprint" ""
			(at 177.8 172.72 0)
			(effects
				(font
					(size 1.27 1.27)
					(thickness 0.15)
				)
				(justify left bottom)
				(hide yes)
			)
		)
		(property "Datasheet" ""
			(at 177.8 177.8 0)
			(effects
				(font
					(size 1.27 1.27)
					(thickness 0.15)
				)
				(justify left bottom)
				(hide yes)
			)
		)
		(property "Description" ""
			(at 168.91 165.1 0)
			(effects
				(font
					(size 1.27 1.27)
				)
				(hide yes)
			)
		)
		(property "Author" "Antmicro"
			(at 177.8 172.72 0)
			(effects
				(font
					(size 1.27 1.27)
					(thickness 0.15)
				)
				(justify left bottom)
				(hide yes)
			)
		)
		(property "License" "Apache-2.0"
			(at 177.8 175.26 0)
			(effects
				(font
					(size 1.27 1.27)
					(thickness 0.15)
				)
				(justify left bottom)
				(hide yes)
			)
		)
		(pin "1"
		)
		(instances
			(project "cm4-baseboard"
				(path ""
					(reference "#PWR0222")
					(unit 1)
				)
			)
		)
	)
	(symbol
		(lib_id "antmicropower:GND")
		(at 185.42 165.1 0)
		(unit 1)
		(exclude_from_sim no)
		(in_bom yes)
		(on_board yes)
		(dnp no)
		(fields_autoplaced yes)
		(property "Reference" "#PWR0228"
			(at 194.31 167.64 0)
			(effects
				(font
					(size 1.27 1.27)
					(thickness 0.15)
				)
				(justify left bottom)
				(hide yes)
			)
		)
		(property "Value" "GND"
			(at 183.4098 170.18 0)
			(effects
				(font
					(size 1.27 1.27)
					(thickness 0.15)
				)
				(justify left bottom)
			)
		)
		(property "Footprint" ""
			(at 194.31 172.72 0)
			(effects
				(font
					(size 1.27 1.27)
					(thickness 0.15)
				)
				(justify left bottom)
				(hide yes)
			)
		)
		(property "Datasheet" ""
			(at 194.31 177.8 0)
			(effects
				(font
					(size 1.27 1.27)
					(thickness 0.15)
				)
				(justify left bottom)
				(hide yes)
			)
		)
		(property "Description" ""
			(at 185.42 165.1 0)
			(effects
				(font
					(size 1.27 1.27)
				)
				(hide yes)
			)
		)
		(property "Author" "Antmicro"
			(at 194.31 172.72 0)
			(effects
				(font
					(size 1.27 1.27)
					(thickness 0.15)
				)
				(justify left bottom)
				(hide yes)
			)
		)
		(property "License" "Apache-2.0"
			(at 194.31 175.26 0)
			(effects
				(font
					(size 1.27 1.27)
					(thickness 0.15)
				)
				(justify left bottom)
				(hide yes)
			)
		)
		(pin "1"
		)
		(instances
			(project "cm4-baseboard"
				(path ""
					(reference "#PWR0228")
					(unit 1)
				)
			)
		)
	)
	(symbol
		(lib_id "antmicroResistors0402:R_1k_0402")
		(at 80.01 59.69 0)
		(unit 1)
		(exclude_from_sim no)
		(in_bom yes)
		(on_board yes)
		(dnp no)
		(property "Reference" "R207"
			(at 82.55 57.15 0)
			(effects
				(font
					(size 1.27 1.27)
					(thickness 0.15)
				)
			)
		)
		(property "Value" "R_1k_0402"
			(at 100.33 72.39 0)
			(effects
				(font
					(size 1.27 1.27)
					(thickness 0.15)
				)
				(justify left bottom)
				(hide yes)
			)
		)
		(property "Footprint" "antmicro-footprints:R_0402_1005Metric"
			(at 100.33 74.93 0)
			(effects
				(font
					(size 1.27 1.27)
					(thickness 0.15)
				)
				(justify left bottom)
				(hide yes)
			)
		)
		(property "Datasheet" "https://www.bourns.com/docs/product-datasheets/cr.pdf"
			(at 100.33 77.47 0)
			(effects
				(font
					(size 1.27 1.27)
					(thickness 0.15)
				)
				(justify left bottom)
				(hide yes)
			)
		)
		(property "Description" ""
			(at 80.01 59.69 0)
			(effects
				(font
					(size 1.27 1.27)
				)
				(hide yes)
			)
		)
		(property "MPN" "CR0402-FX-1001GLF"
			(at 100.33 80.01 0)
			(effects
				(font
					(size 1.27 1.27)
					(thickness 0.15)
				)
				(justify left bottom)
				(hide yes)
			)
		)
		(property "Manufacturer" "Bourns"
			(at 100.33 82.55 0)
			(effects
				(font
					(size 1.27 1.27)
					(thickness 0.15)
				)
				(justify left bottom)
				(hide yes)
			)
		)
		(property "License" "Apache-2.0"
			(at 100.33 85.09 0)
			(effects
				(font
					(size 1.27 1.27)
					(thickness 0.15)
				)
				(justify left bottom)
				(hide yes)
			)
		)
		(property "Author" "Antmicro"
			(at 100.33 87.63 0)
			(effects
				(font
					(size 1.27 1.27)
					(thickness 0.15)
				)
				(justify left bottom)
				(hide yes)
			)
		)
		(property "Val" "1k"
			(at 82.55 59.69 0)
			(effects
				(font
					(size 1.27 1.27)
					(thickness 0.15)
				)
			)
		)
		(property "Tolerance" "1%"
			(at 100.33 69.85 0)
			(effects
				(font
					(size 1.27 1.27)
				)
				(justify left bottom)
				(hide yes)
			)
		)
		(pin "1"
		)
		(pin "2"
		)
		(instances
			(project "cm4-baseboard"
				(path ""
					(reference "R207")
					(unit 1)
				)
			)
		)
	)
	(symbol
		(lib_id "antmicropower:+3V3")
		(at 240.03 55.88 0)
		(unit 1)
		(exclude_from_sim no)
		(in_bom yes)
		(on_board yes)
		(dnp no)
		(property "Reference" "#PWR0232"
			(at 255.27 55.88 0)
			(effects
				(font
					(size 1.27 1.27)
					(thickness 0.15)
				)
				(justify left bottom)
				(hide yes)
			)
		)
		(property "Value" "+3V3"
			(at 237.49 52.07 0)
			(effects
				(font
					(size 1.27 1.27)
					(thickness 0.15)
				)
				(justify left)
			)
		)
		(property "Footprint" ""
			(at 255.27 63.5 0)
			(effects
				(font
					(size 1.27 1.27)
					(thickness 0.15)
				)
				(justify left bottom)
				(hide yes)
			)
		)
		(property "Datasheet" ""
			(at 255.27 66.04 0)
			(effects
				(font
					(size 1.27 1.27)
					(thickness 0.15)
				)
				(justify left bottom)
				(hide yes)
			)
		)
		(property "Description" ""
			(at 240.03 55.88 0)
			(effects
				(font
					(size 1.27 1.27)
				)
				(hide yes)
			)
		)
		(property "Author" "Antmicro"
			(at 255.27 58.42 0)
			(effects
				(font
					(size 1.27 1.27)
					(thickness 0.15)
				)
				(justify left bottom)
				(hide yes)
			)
		)
		(property "License" "Apache-2.0"
			(at 255.27 60.96 0)
			(effects
				(font
					(size 1.27 1.27)
					(thickness 0.15)
				)
				(justify left bottom)
				(hide yes)
			)
		)
		(pin "1"
		)
		(instances
			(project "cm4-baseboard"
				(path ""
					(reference "#PWR0232")
					(unit 1)
				)
			)
		)
	)
	(symbol
		(lib_id "antmicroTestPoints:TP_0.75mm_SMD")
		(at 90.17 151.13 0)
		(mirror x)
		(unit 1)
		(exclude_from_sim no)
		(in_bom no)
		(on_board yes)
		(dnp no)
		(property "Reference" "TP207"
			(at 94.615 151.13 0)
			(effects
				(font
					(size 1.27 1.27)
					(thickness 0.15)
				)
				(justify left)
			)
		)
		(property "Value" "TP_0.75mm_SMD"
			(at 105.41 143.51 0)
			(effects
				(font
					(size 1.27 1.27)
					(thickness 0.15)
				)
				(justify left bottom)
				(hide yes)
			)
		)
		(property "Footprint" "antmicro-footprints:TP_SMD_0.75mm"
			(at 100.965 144.78 0)
			(effects
				(font
					(size 1.27 1.27)
					(thickness 0.15)
				)
				(justify left bottom)
				(hide yes)
			)
		)
		(property "Datasheet" ""
			(at 107.95 138.43 0)
			(effects
				(font
					(size 1.27 1.27)
					(thickness 0.15)
				)
				(justify left bottom)
				(hide yes)
			)
		)
		(property "Description" ""
			(at 90.17 151.13 0)
			(effects
				(font
					(size 1.27 1.27)
				)
				(hide yes)
			)
		)
		(property "Author" "Antmicro"
			(at 100.965 142.24 0)
			(effects
				(font
					(size 1.27 1.27)
					(thickness 0.15)
				)
				(justify left bottom)
				(hide yes)
			)
		)
		(property "License" "Apache-2.0"
			(at 100.965 139.7 0)
			(effects
				(font
					(size 1.27 1.27)
					(thickness 0.15)
				)
				(justify left bottom)
				(hide yes)
			)
		)
		(property "MPN" ""
			(at 100.965 139.7 0)
			(effects
				(font
					(size 1.27 1.27)
					(thickness 0.15)
				)
				(justify left bottom)
				(hide yes)
			)
		)
		(property "Manufacturer" ""
			(at 100.965 144.78 0)
			(effects
				(font
					(size 1.27 1.27)
					(thickness 0.15)
				)
				(justify left bottom)
				(hide yes)
			)
		)
		(pin "1"
		)
		(instances
			(project "cm4-baseboard"
				(path ""
					(reference "TP207")
					(unit 1)
				)
			)
		)
	)
	(symbol
		(lib_id "antmicroLogicTranslatorsLevelShifters:TXB0104_UQFN")
		(at 250.19 212.09 0)
		(unit 1)
		(exclude_from_sim no)
		(in_bom yes)
		(on_board yes)
		(dnp no)
		(fields_autoplaced yes)
		(property "Reference" "U203"
			(at 260.35 204.47 0)
			(effects
				(font
					(size 1.27 1.27)
					(thickness 0.15)
				)
			)
		)
		(property "Value" "TXB0104_UQFN"
			(at 260.35 207.01 0)
			(effects
				(font
					(size 1.27 1.27)
					(thickness 0.15)
				)
				(hide yes)
			)
		)
		(property "Footprint" "antmicro-footprints:UQFN-12_2x1.7mm_P0.4mm_Texas_RUT"
			(at 285.75 222.25 0)
			(effects
				(font
					(size 1.27 1.27)
					(thickness 0.15)
				)
				(justify left bottom)
				(hide yes)
			)
		)
		(property "Datasheet" "http://www.ti.com/lit/ds/symlink/txb0104.pdf"
			(at 285.75 224.79 0)
			(effects
				(font
					(size 1.27 1.27)
					(thickness 0.15)
				)
				(justify left bottom)
				(hide yes)
			)
		)
		(property "Description" ""
			(at 250.19 212.09 0)
			(effects
				(font
					(size 1.27 1.27)
				)
				(hide yes)
			)
		)
		(property "Manufacturer" "Texas Instruments"
			(at 285.75 227.33 0)
			(effects
				(font
					(size 1.27 1.27)
					(thickness 0.15)
				)
				(justify left bottom)
				(hide yes)
			)
		)
		(property "MPN" "TXB0104RUTR"
			(at 260.35 207.01 0)
			(effects
				(font
					(size 1.27 1.27)
					(thickness 0.15)
				)
			)
		)
		(property "Author" "Antmicro"
			(at 285.75 232.41 0)
			(effects
				(font
					(size 1.27 1.27)
					(thickness 0.15)
				)
				(justify left bottom)
				(hide yes)
			)
		)
		(property "License" "Apache-2.0"
			(at 285.75 234.95 0)
			(effects
				(font
					(size 1.27 1.27)
					(thickness 0.15)
				)
				(justify left bottom)
				(hide yes)
			)
		)
		(pin "1"
		)
		(pin "10"
		)
		(pin "11"
		)
		(pin "12"
		)
		(pin "2"
		)
		(pin "3"
		)
		(pin "4"
		)
		(pin "5"
		)
		(pin "6"
		)
		(pin "7"
		)
		(pin "8"
		)
		(pin "9"
		)
		(instances
			(project "cm4-baseboard"
				(path ""
					(reference "U203")
					(unit 1)
				)
			)
		)
	)
	(symbol
		(lib_id "antmicropower:+1V8")
		(at 38.1 144.78 0)
		(unit 1)
		(exclude_from_sim no)
		(in_bom yes)
		(on_board yes)
		(dnp no)
		(property "Reference" "#PWR0203"
			(at 53.34 147.32 0)
			(effects
				(font
					(size 1.27 1.27)
					(thickness 0.15)
				)
				(justify left bottom)
				(hide yes)
			)
		)
		(property "Value" "+1V8"
			(at 34.29 143.51 0)
			(effects
				(font
					(size 1.27 1.27)
					(thickness 0.15)
				)
			)
		)
		(property "Footprint" ""
			(at 53.34 152.4 0)
			(effects
				(font
					(size 1.27 1.27)
					(thickness 0.15)
				)
				(justify left bottom)
				(hide yes)
			)
		)
		(property "Datasheet" ""
			(at 53.34 154.94 0)
			(effects
				(font
					(size 1.27 1.27)
					(thickness 0.15)
				)
				(justify left bottom)
				(hide yes)
			)
		)
		(property "Description" ""
			(at 38.1 144.78 0)
			(effects
				(font
					(size 1.27 1.27)
				)
				(hide yes)
			)
		)
		(property "Author" "Antmicro"
			(at 53.34 149.86 0)
			(effects
				(font
					(size 1.27 1.27)
					(thickness 0.15)
				)
				(justify left bottom)
				(hide yes)
			)
		)
		(property "License" "Apache-2.0"
			(at 53.34 152.4 0)
			(effects
				(font
					(size 1.27 1.27)
					(thickness 0.15)
				)
				(justify left bottom)
				(hide yes)
			)
		)
		(pin "1"
		)
		(instances
			(project "cm4-baseboard"
				(path ""
					(reference "#PWR0203")
					(unit 1)
				)
			)
		)
	)
	(symbol
		(lib_id "antmicropower:GND")
		(at 196.85 223.52 0)
		(unit 1)
		(exclude_from_sim no)
		(in_bom yes)
		(on_board yes)
		(dnp no)
		(property "Reference" "#PWR032"
			(at 205.74 226.06 0)
			(effects
				(font
					(size 1.27 1.27)
					(thickness 0.15)
				)
				(justify left bottom)
				(hide yes)
			)
		)
		(property "Value" "GND"
			(at 194.945 227.965 0)
			(effects
				(font
					(size 1.27 1.27)
					(thickness 0.15)
				)
				(justify left bottom)
			)
		)
		(property "Footprint" ""
			(at 205.74 231.14 0)
			(effects
				(font
					(size 1.27 1.27)
					(thickness 0.15)
				)
				(justify left bottom)
				(hide yes)
			)
		)
		(property "Datasheet" ""
			(at 205.74 236.22 0)
			(effects
				(font
					(size 1.27 1.27)
					(thickness 0.15)
				)
				(justify left bottom)
				(hide yes)
			)
		)
		(property "Description" ""
			(at 196.85 223.52 0)
			(effects
				(font
					(size 1.27 1.27)
				)
				(hide yes)
			)
		)
		(property "Author" "Antmicro"
			(at 205.74 231.14 0)
			(effects
				(font
					(size 1.27 1.27)
					(thickness 0.15)
				)
				(justify left bottom)
				(hide yes)
			)
		)
		(property "License" "Apache-2.0"
			(at 205.74 233.68 0)
			(effects
				(font
					(size 1.27 1.27)
					(thickness 0.15)
				)
				(justify left bottom)
				(hide yes)
			)
		)
		(pin "1"
		)
		(instances
			(project "cm4-baseboard"
				(path ""
					(reference "#PWR032")
					(unit 1)
				)
			)
		)
	)
	(symbol
		(lib_id "antmicropower:GND")
		(at 134.62 209.55 0)
		(unit 1)
		(exclude_from_sim no)
		(in_bom yes)
		(on_board yes)
		(dnp no)
		(property "Reference" "#PWR0217"
			(at 134.62 215.9 0)
			(effects
				(font
					(size 1.27 1.27)
				)
				(justify left bottom)
				(hide yes)
			)
		)
		(property "Value" "GND"
			(at 134.62 213.36 0)
			(effects
				(font
					(size 1.27 1.27)
				)
			)
		)
		(property "Footprint" ""
			(at 143.51 217.17 0)
			(effects
				(font
					(size 1.27 1.27)
					(thickness 0.15)
				)
				(justify left bottom)
				(hide yes)
			)
		)
		(property "Datasheet" ""
			(at 143.51 222.25 0)
			(effects
				(font
					(size 1.27 1.27)
					(thickness 0.15)
				)
				(justify left bottom)
				(hide yes)
			)
		)
		(property "Description" ""
			(at 134.62 209.55 0)
			(effects
				(font
					(size 1.27 1.27)
				)
				(hide yes)
			)
		)
		(property "Author" "Antmicro"
			(at 143.51 217.17 0)
			(effects
				(font
					(size 1.27 1.27)
					(thickness 0.15)
				)
				(justify left bottom)
				(hide yes)
			)
		)
		(property "License" "Apache-2.0"
			(at 143.51 219.71 0)
			(effects
				(font
					(size 1.27 1.27)
					(thickness 0.15)
				)
				(justify left bottom)
				(hide yes)
			)
		)
		(pin "1"
		)
		(instances
			(project "cm4-baseboard"
				(path ""
					(reference "#PWR0217")
					(unit 1)
				)
			)
		)
	)
	(symbol
		(lib_id "antmicroResistors0402:R_0R_0402")
		(at 196.85 115.57 0)
		(unit 1)
		(exclude_from_sim no)
		(in_bom yes)
		(on_board yes)
		(dnp no)
		(property "Reference" "R228"
			(at 194.31 114.3 0)
			(effects
				(font
					(size 1.27 1.27)
				)
			)
		)
		(property "Value" "R_0R_0402"
			(at 196.85 119.38 0)
			(effects
				(font
					(size 1.27 1.27)
				)
				(justify left bottom)
				(hide yes)
			)
		)
		(property "Footprint" "antmicro-footprints:R_0402_1005Metric"
			(at 201.93 110.49 0)
			(effects
				(font
					(size 1.524 1.524)
				)
				(justify left bottom)
				(hide yes)
			)
		)
		(property "Datasheet" "https://industrial.panasonic.com/cdbs/www-data/pdf/RDA0000/AOA0000C301.pdf"
			(at 196.85 115.57 0)
			(effects
				(font
					(size 1.27 1.27)
				)
				(justify left bottom)
				(hide yes)
			)
		)
		(property "Description" ""
			(at 196.85 115.57 0)
			(effects
				(font
					(size 1.27 1.27)
				)
				(hide yes)
			)
		)
		(property "Manufacturer" "Panasonic"
			(at 201.93 105.41 0)
			(effects
				(font
					(size 1.524 1.524)
				)
				(justify left bottom)
				(hide yes)
			)
		)
		(property "MPN" "ERJ2GE0R00X"
			(at 201.93 107.95 0)
			(effects
				(font
					(size 1.524 1.524)
				)
				(justify left bottom)
				(hide yes)
			)
		)
		(property "Val" "0R"
			(at 203.2 114.3 0)
			(effects
				(font
					(size 1.27 1.27)
				)
			)
		)
		(property "License" "Apache-2.0"
			(at 217.17 140.97 0)
			(effects
				(font
					(size 1.27 1.27)
					(thickness 0.15)
				)
				(justify left bottom)
				(hide yes)
			)
		)
		(property "Author" "Antmicro"
			(at 217.17 143.51 0)
			(effects
				(font
					(size 1.27 1.27)
					(thickness 0.15)
				)
				(justify left bottom)
				(hide yes)
			)
		)
		(property "Tolerance" "~"
			(at 217.17 125.73 0)
			(effects
				(font
					(size 1.27 1.27)
				)
				(justify left bottom)
				(hide yes)
			)
		)
		(property "Current" "1A"
			(at 199.39 113.665 0)
			(effects
				(font
					(size 1.27 1.27)
					(thickness 0.15)
				)
				(hide yes)
			)
		)
		(pin "1"
		)
		(pin "2"
		)
		(instances
			(project "cm4-baseboard"
				(path ""
					(reference "R228")
					(unit 1)
				)
			)
		)
	)
	(symbol
		(lib_id "antmicroResistors0402:R_2k2_0402")
		(at 148.59 228.6 90)
		(unit 1)
		(exclude_from_sim no)
		(in_bom yes)
		(on_board yes)
		(dnp no)
		(fields_autoplaced yes)
		(property "Reference" "R215"
			(at 151.13 224.7899 90)
			(effects
				(font
					(size 1.27 1.27)
				)
				(justify right)
			)
		)
		(property "Value" "R_2k2_0402"
			(at 161.29 208.28 0)
			(effects
				(font
					(size 1.27 1.27)
					(thickness 0.15)
				)
				(justify left bottom)
				(hide yes)
			)
		)
		(property "Footprint" "antmicro-footprints:R_0402_1005Metric"
			(at 163.83 208.28 0)
			(effects
				(font
					(size 1.27 1.27)
					(thickness 0.15)
				)
				(justify left bottom)
				(hide yes)
			)
		)
		(property "Datasheet" "https://www.bourns.com/docs/product-datasheets/cr.pdf"
			(at 166.37 208.28 0)
			(effects
				(font
					(size 1.27 1.27)
					(thickness 0.15)
				)
				(justify left bottom)
				(hide yes)
			)
		)
		(property "Description" ""
			(at 148.59 228.6 0)
			(effects
				(font
					(size 1.27 1.27)
				)
				(hide yes)
			)
		)
		(property "Manufacturer" "Bourns"
			(at 171.45 208.28 0)
			(effects
				(font
					(size 1.27 1.27)
					(thickness 0.15)
				)
				(justify left bottom)
				(hide yes)
			)
		)
		(property "MPN" "CR0402-FX-2201GLF"
			(at 168.91 208.28 0)
			(effects
				(font
					(size 1.27 1.27)
					(thickness 0.15)
				)
				(justify left bottom)
				(hide yes)
			)
		)
		(property "Val" "2k2"
			(at 151.13 227.3299 90)
			(effects
				(font
					(size 1.27 1.27)
					(thickness 0.15)
				)
				(justify right)
			)
		)
		(property "License" "Apache-2.0"
			(at 173.99 208.28 0)
			(effects
				(font
					(size 1.27 1.27)
					(thickness 0.15)
				)
				(justify left bottom)
				(hide yes)
			)
		)
		(property "Author" "Antmicro"
			(at 176.53 208.28 0)
			(effects
				(font
					(size 1.27 1.27)
					(thickness 0.15)
				)
				(justify left bottom)
				(hide yes)
			)
		)
		(property "Tolerance" "1%"
			(at 158.75 208.28 0)
			(effects
				(font
					(size 1.27 1.27)
				)
				(justify left bottom)
				(hide yes)
			)
		)
		(pin "1"
		)
		(pin "2"
		)
		(instances
			(project "cm4-baseboard"
				(path ""
					(reference "R215")
					(unit 1)
				)
			)
		)
	)
	(symbol
		(lib_id "antmicropower:+5V")
		(at 30.48 193.04 0)
		(unit 1)
		(exclude_from_sim no)
		(in_bom yes)
		(on_board yes)
		(dnp no)
		(fields_autoplaced yes)
		(property "Reference" "#PWR0201"
			(at 45.72 195.58 0)
			(effects
				(font
					(size 1.27 1.27)
					(thickness 0.15)
				)
				(justify left bottom)
				(hide yes)
			)
		)
		(property "Value" "+5V"
			(at 30.48 187.96 0)
			(effects
				(font
					(size 1.27 1.27)
					(thickness 0.15)
				)
			)
		)
		(property "Footprint" ""
			(at 45.72 200.66 0)
			(effects
				(font
					(size 1.27 1.27)
					(thickness 0.15)
				)
				(justify left bottom)
				(hide yes)
			)
		)
		(property "Datasheet" ""
			(at 45.72 203.2 0)
			(effects
				(font
					(size 1.27 1.27)
					(thickness 0.15)
				)
				(justify left bottom)
				(hide yes)
			)
		)
		(property "Description" ""
			(at 30.48 193.04 0)
			(effects
				(font
					(size 1.27 1.27)
				)
				(hide yes)
			)
		)
		(property "Author" "Antmicro"
			(at 45.72 200.66 0)
			(effects
				(font
					(size 1.27 1.27)
					(thickness 0.15)
				)
				(justify left bottom)
				(hide yes)
			)
		)
		(property "License" "Apache-2.0"
			(at 45.72 203.2 0)
			(effects
				(font
					(size 1.27 1.27)
					(thickness 0.15)
				)
				(justify left bottom)
				(hide yes)
			)
		)
		(pin "1"
		)
		(instances
			(project "cm4-baseboard"
				(path ""
					(reference "#PWR0201")
					(unit 1)
				)
			)
		)
	)
	(symbol
		(lib_id "antmicroTestPoints:TP_0.75mm_SMD")
		(at 90.17 156.21 0)
		(mirror x)
		(unit 1)
		(exclude_from_sim no)
		(in_bom no)
		(on_board yes)
		(dnp no)
		(property "Reference" "TP209"
			(at 94.615 156.21 0)
			(effects
				(font
					(size 1.27 1.27)
					(thickness 0.15)
				)
				(justify left)
			)
		)
		(property "Value" "TP_0.75mm_SMD"
			(at 105.41 148.59 0)
			(effects
				(font
					(size 1.27 1.27)
					(thickness 0.15)
				)
				(justify left bottom)
				(hide yes)
			)
		)
		(property "Footprint" "antmicro-footprints:TP_SMD_0.75mm"
			(at 100.965 149.86 0)
			(effects
				(font
					(size 1.27 1.27)
					(thickness 0.15)
				)
				(justify left bottom)
				(hide yes)
			)
		)
		(property "Datasheet" ""
			(at 107.95 143.51 0)
			(effects
				(font
					(size 1.27 1.27)
					(thickness 0.15)
				)
				(justify left bottom)
				(hide yes)
			)
		)
		(property "Description" ""
			(at 90.17 156.21 0)
			(effects
				(font
					(size 1.27 1.27)
				)
				(hide yes)
			)
		)
		(property "Author" "Antmicro"
			(at 100.965 147.32 0)
			(effects
				(font
					(size 1.27 1.27)
					(thickness 0.15)
				)
				(justify left bottom)
				(hide yes)
			)
		)
		(property "License" "Apache-2.0"
			(at 100.965 144.78 0)
			(effects
				(font
					(size 1.27 1.27)
					(thickness 0.15)
				)
				(justify left bottom)
				(hide yes)
			)
		)
		(property "MPN" ""
			(at 100.965 144.78 0)
			(effects
				(font
					(size 1.27 1.27)
					(thickness 0.15)
				)
				(justify left bottom)
				(hide yes)
			)
		)
		(property "Manufacturer" ""
			(at 100.965 149.86 0)
			(effects
				(font
					(size 1.27 1.27)
					(thickness 0.15)
				)
				(justify left bottom)
				(hide yes)
			)
		)
		(pin "1"
		)
		(instances
			(project "cm4-baseboard"
				(path ""
					(reference "TP209")
					(unit 1)
				)
			)
		)
	)
	(symbol
		(lib_id "antmicropower:+5V")
		(at 176.53 193.04 0)
		(unit 1)
		(exclude_from_sim no)
		(in_bom yes)
		(on_board yes)
		(dnp no)
		(fields_autoplaced yes)
		(property "Reference" "#PWR0229"
			(at 191.77 195.58 0)
			(effects
				(font
					(size 1.27 1.27)
					(thickness 0.15)
				)
				(justify left bottom)
				(hide yes)
			)
		)
		(property "Value" "+5V"
			(at 176.53 187.96 0)
			(effects
				(font
					(size 1.27 1.27)
					(thickness 0.15)
				)
			)
		)
		(property "Footprint" ""
			(at 191.77 200.66 0)
			(effects
				(font
					(size 1.27 1.27)
					(thickness 0.15)
				)
				(justify left bottom)
				(hide yes)
			)
		)
		(property "Datasheet" ""
			(at 191.77 203.2 0)
			(effects
				(font
					(size 1.27 1.27)
					(thickness 0.15)
				)
				(justify left bottom)
				(hide yes)
			)
		)
		(property "Description" ""
			(at 176.53 193.04 0)
			(effects
				(font
					(size 1.27 1.27)
				)
				(hide yes)
			)
		)
		(property "Author" "Antmicro"
			(at 191.77 200.66 0)
			(effects
				(font
					(size 1.27 1.27)
					(thickness 0.15)
				)
				(justify left bottom)
				(hide yes)
			)
		)
		(property "License" "Apache-2.0"
			(at 191.77 203.2 0)
			(effects
				(font
					(size 1.27 1.27)
					(thickness 0.15)
				)
				(justify left bottom)
				(hide yes)
			)
		)
		(pin "1"
		)
		(instances
			(project "cm4-baseboard"
				(path ""
					(reference "#PWR0229")
					(unit 1)
				)
			)
		)
	)
	(symbol
		(lib_id "antmicroTransistorsFETsMOSFETsSingle:SSM3J332R")
		(at 44.45 204.47 270)
		(mirror x)
		(unit 1)
		(exclude_from_sim no)
		(in_bom yes)
		(on_board yes)
		(dnp no)
		(property "Reference" "Q202"
			(at 53.34 200.66 90)
			(effects
				(font
					(size 1.27 1.27)
					(thickness 0.15)
				)
			)
		)
		(property "Value" "SSM3J332R"
			(at 53.34 203.2 90)
			(effects
				(font
					(size 1.27 1.27)
					(thickness 0.15)
				)
				(hide yes)
			)
		)
		(property "Footprint" "antmicro-footprints:SOT-23-3"
			(at 39.37 190.5 0)
			(effects
				(font
					(size 1.27 1.27)
					(thickness 0.15)
				)
				(justify left bottom)
				(hide yes)
			)
		)
		(property "Datasheet" "https://www.mouser.com/datasheet/2/408/SSM3J332R_datasheet_en_20181015-1150575.pdf"
			(at 36.83 190.5 0)
			(effects
				(font
					(size 1.27 1.27)
					(thickness 0.15)
				)
				(justify left bottom)
				(hide yes)
			)
		)
		(property "Description" ""
			(at 44.45 204.47 0)
			(effects
				(font
					(size 1.27 1.27)
				)
				(hide yes)
			)
		)
		(property "MPN" "SSM3J332R,LF"
			(at 46.99 203.2 90)
			(effects
				(font
					(size 1.27 1.27)
					(thickness 0.15)
				)
				(justify left bottom)
			)
		)
		(property "Manufacturer" "Toshiba"
			(at 31.75 190.5 0)
			(effects
				(font
					(size 1.27 1.27)
					(thickness 0.15)
				)
				(justify left bottom)
				(hide yes)
			)
		)
		(property "Author" "Antmicro"
			(at 29.21 190.5 0)
			(effects
				(font
					(size 1.27 1.27)
					(thickness 0.15)
				)
				(justify left bottom)
				(hide yes)
			)
		)
		(property "License" "Apache-2.0"
			(at 26.67 190.5 0)
			(effects
				(font
					(size 1.27 1.27)
					(thickness 0.15)
				)
				(justify left bottom)
				(hide yes)
			)
		)
		(pin "1"
		)
		(pin "2"
		)
		(pin "3"
		)
		(instances
			(project "cm4-baseboard"
				(path ""
					(reference "Q202")
					(unit 1)
				)
			)
		)
	)
	(symbol
		(lib_id "antmicroCapacitors0402:C_100n_0402")
		(at 293.37 93.98 90)
		(unit 1)
		(exclude_from_sim no)
		(in_bom yes)
		(on_board yes)
		(dnp no)
		(fields_autoplaced yes)
		(property "Reference" "C210"
			(at 295.91 90.1635 90)
			(effects
				(font
					(size 1.27 1.27)
				)
				(justify right)
			)
		)
		(property "Value" "C_100n_0402"
			(at 297.18 93.98 0)
			(effects
				(font
					(size 1.27 1.27)
				)
				(justify left bottom)
				(hide yes)
			)
		)
		(property "Footprint" "antmicro-footprints:C_0402_1005Metric"
			(at 288.29 88.9 0)
			(effects
				(font
					(size 1.524 1.524)
				)
				(justify left bottom)
				(hide yes)
			)
		)
		(property "Datasheet" "https://www.murata.com/products/productdetail?partno=GRM155R61H104KE14%23"
			(at 293.37 93.98 0)
			(effects
				(font
					(size 1.27 1.27)
				)
				(justify left bottom)
				(hide yes)
			)
		)
		(property "Description" ""
			(at 293.37 93.98 0)
			(effects
				(font
					(size 1.27 1.27)
				)
				(hide yes)
			)
		)
		(property "Manufacturer" "Murata"
			(at 283.21 88.9 0)
			(effects
				(font
					(size 1.524 1.524)
				)
				(justify left bottom)
				(hide yes)
			)
		)
		(property "MPN" "GRM155R61H104KE14D"
			(at 285.75 88.9 0)
			(effects
				(font
					(size 1.524 1.524)
				)
				(justify left bottom)
				(hide yes)
			)
		)
		(property "Val" "100n"
			(at 295.91 92.7035 90)
			(effects
				(font
					(size 1.27 1.27)
				)
				(justify right)
			)
		)
		(property "License" "Apache-2.0"
			(at 316.23 73.66 0)
			(effects
				(font
					(size 1.27 1.27)
					(thickness 0.15)
				)
				(justify left bottom)
				(hide yes)
			)
		)
		(property "Author" "Antmicro"
			(at 318.77 73.66 0)
			(effects
				(font
					(size 1.27 1.27)
					(thickness 0.15)
				)
				(justify left bottom)
				(hide yes)
			)
		)
		(property "Voltage" "50V"
			(at 321.31 73.66 0)
			(effects
				(font
					(size 1.27 1.27)
				)
				(justify left bottom)
				(hide yes)
			)
		)
		(property "Dielectric" "X5R"
			(at 323.85 73.66 0)
			(effects
				(font
					(size 1.27 1.27)
				)
				(justify left bottom)
				(hide yes)
			)
		)
		(pin "1"
		)
		(pin "2"
		)
		(instances
			(project "cm4-baseboard"
				(path ""
					(reference "C210")
					(unit 1)
				)
			)
		)
	)
	(symbol
		(lib_id "antmicroTestPoints:TP_0.75mm_SMD")
		(at 90.17 146.05 0)
		(mirror x)
		(unit 1)
		(exclude_from_sim no)
		(in_bom no)
		(on_board yes)
		(dnp no)
		(property "Reference" "TP205"
			(at 94.615 146.05 0)
			(effects
				(font
					(size 1.27 1.27)
					(thickness 0.15)
				)
				(justify left)
			)
		)
		(property "Value" "TP_0.75mm_SMD"
			(at 105.41 138.43 0)
			(effects
				(font
					(size 1.27 1.27)
					(thickness 0.15)
				)
				(justify left bottom)
				(hide yes)
			)
		)
		(property "Footprint" "antmicro-footprints:TP_SMD_0.75mm"
			(at 100.965 139.7 0)
			(effects
				(font
					(size 1.27 1.27)
					(thickness 0.15)
				)
				(justify left bottom)
				(hide yes)
			)
		)
		(property "Datasheet" ""
			(at 107.95 133.35 0)
			(effects
				(font
					(size 1.27 1.27)
					(thickness 0.15)
				)
				(justify left bottom)
				(hide yes)
			)
		)
		(property "Description" ""
			(at 90.17 146.05 0)
			(effects
				(font
					(size 1.27 1.27)
				)
				(hide yes)
			)
		)
		(property "Author" "Antmicro"
			(at 100.965 137.16 0)
			(effects
				(font
					(size 1.27 1.27)
					(thickness 0.15)
				)
				(justify left bottom)
				(hide yes)
			)
		)
		(property "License" "Apache-2.0"
			(at 100.965 134.62 0)
			(effects
				(font
					(size 1.27 1.27)
					(thickness 0.15)
				)
				(justify left bottom)
				(hide yes)
			)
		)
		(property "MPN" ""
			(at 100.965 134.62 0)
			(effects
				(font
					(size 1.27 1.27)
					(thickness 0.15)
				)
				(justify left bottom)
				(hide yes)
			)
		)
		(property "Manufacturer" ""
			(at 100.965 139.7 0)
			(effects
				(font
					(size 1.27 1.27)
					(thickness 0.15)
				)
				(justify left bottom)
				(hide yes)
			)
		)
		(pin "1"
		)
		(instances
			(project "cm4-baseboard"
				(path ""
					(reference "TP205")
					(unit 1)
				)
			)
		)
	)
	(symbol
		(lib_id "antmicropower:GND")
		(at 340.36 161.29 0)
		(unit 1)
		(exclude_from_sim no)
		(in_bom yes)
		(on_board yes)
		(dnp no)
		(fields_autoplaced yes)
		(property "Reference" "#PWR0227"
			(at 349.25 163.83 0)
			(effects
				(font
					(size 1.27 1.27)
					(thickness 0.15)
				)
				(justify left bottom)
				(hide yes)
			)
		)
		(property "Value" "GND"
			(at 338.3498 166.37 0)
			(effects
				(font
					(size 1.27 1.27)
					(thickness 0.15)
				)
				(justify left bottom)
			)
		)
		(property "Footprint" ""
			(at 349.25 168.91 0)
			(effects
				(font
					(size 1.27 1.27)
					(thickness 0.15)
				)
				(justify left bottom)
				(hide yes)
			)
		)
		(property "Datasheet" ""
			(at 349.25 173.99 0)
			(effects
				(font
					(size 1.27 1.27)
					(thickness 0.15)
				)
				(justify left bottom)
				(hide yes)
			)
		)
		(property "Description" ""
			(at 340.36 161.29 0)
			(effects
				(font
					(size 1.27 1.27)
				)
				(hide yes)
			)
		)
		(property "Author" "Antmicro"
			(at 349.25 168.91 0)
			(effects
				(font
					(size 1.27 1.27)
					(thickness 0.15)
				)
				(justify left bottom)
				(hide yes)
			)
		)
		(property "License" "Apache-2.0"
			(at 349.25 171.45 0)
			(effects
				(font
					(size 1.27 1.27)
					(thickness 0.15)
				)
				(justify left bottom)
				(hide yes)
			)
		)
		(pin "1"
		)
		(instances
			(project "cm4-baseboard"
				(path ""
					(reference "#PWR0227")
					(unit 1)
				)
			)
		)
	)
	(symbol
		(lib_id "antmicropower:GND")
		(at 275.59 81.28 0)
		(unit 1)
		(exclude_from_sim no)
		(in_bom yes)
		(on_board yes)
		(dnp no)
		(fields_autoplaced yes)
		(property "Reference" "#PWR0252"
			(at 275.59 87.63 0)
			(effects
				(font
					(size 1.27 1.27)
				)
				(justify left bottom)
				(hide yes)
			)
		)
		(property "Value" "GND"
			(at 275.59 86.36 0)
			(effects
				(font
					(size 1.27 1.27)
				)
			)
		)
		(property "Footprint" ""
			(at 284.48 88.9 0)
			(effects
				(font
					(size 1.27 1.27)
					(thickness 0.15)
				)
				(justify left bottom)
				(hide yes)
			)
		)
		(property "Datasheet" ""
			(at 284.48 93.98 0)
			(effects
				(font
					(size 1.27 1.27)
					(thickness 0.15)
				)
				(justify left bottom)
				(hide yes)
			)
		)
		(property "Description" ""
			(at 275.59 81.28 0)
			(effects
				(font
					(size 1.27 1.27)
				)
				(hide yes)
			)
		)
		(property "Author" "Antmicro"
			(at 284.48 88.9 0)
			(effects
				(font
					(size 1.27 1.27)
					(thickness 0.15)
				)
				(justify left bottom)
				(hide yes)
			)
		)
		(property "License" "Apache-2.0"
			(at 284.48 91.44 0)
			(effects
				(font
					(size 1.27 1.27)
					(thickness 0.15)
				)
				(justify left bottom)
				(hide yes)
			)
		)
		(pin "1"
		)
		(instances
			(project "cm4-baseboard"
				(path ""
					(reference "#PWR0252")
					(unit 1)
				)
			)
		)
	)
	(symbol
		(lib_id "antmicropower:GND")
		(at 114.3 209.55 0)
		(unit 1)
		(exclude_from_sim no)
		(in_bom yes)
		(on_board yes)
		(dnp no)
		(property "Reference" "#PWR0212"
			(at 114.3 215.9 0)
			(effects
				(font
					(size 1.27 1.27)
				)
				(justify left bottom)
				(hide yes)
			)
		)
		(property "Value" "GND"
			(at 114.3 213.36 0)
			(effects
				(font
					(size 1.27 1.27)
				)
			)
		)
		(property "Footprint" ""
			(at 123.19 217.17 0)
			(effects
				(font
					(size 1.27 1.27)
					(thickness 0.15)
				)
				(justify left bottom)
				(hide yes)
			)
		)
		(property "Datasheet" ""
			(at 123.19 222.25 0)
			(effects
				(font
					(size 1.27 1.27)
					(thickness 0.15)
				)
				(justify left bottom)
				(hide yes)
			)
		)
		(property "Description" ""
			(at 114.3 209.55 0)
			(effects
				(font
					(size 1.27 1.27)
				)
				(hide yes)
			)
		)
		(property "Author" "Antmicro"
			(at 123.19 217.17 0)
			(effects
				(font
					(size 1.27 1.27)
					(thickness 0.15)
				)
				(justify left bottom)
				(hide yes)
			)
		)
		(property "License" "Apache-2.0"
			(at 123.19 219.71 0)
			(effects
				(font
					(size 1.27 1.27)
					(thickness 0.15)
				)
				(justify left bottom)
				(hide yes)
			)
		)
		(pin "1"
		)
		(instances
			(project "cm4-baseboard"
				(path ""
					(reference "#PWR0212")
					(unit 1)
				)
			)
		)
	)
	(symbol
		(lib_id "antmicroResistors0402:R_2k2_0402")
		(at 189.23 276.86 270)
		(mirror x)
		(unit 1)
		(exclude_from_sim no)
		(in_bom yes)
		(on_board yes)
		(dnp no)
		(property "Reference" "R241"
			(at 187.96 273.05 90)
			(effects
				(font
					(size 1.27 1.27)
					(thickness 0.15)
				)
				(justify right)
			)
		)
		(property "Value" "R_2k2_0402"
			(at 176.53 256.54 0)
			(effects
				(font
					(size 1.27 1.27)
					(thickness 0.15)
				)
				(justify left bottom)
				(hide yes)
			)
		)
		(property "Footprint" "antmicro-footprints:R_0402_1005Metric"
			(at 173.99 256.54 0)
			(effects
				(font
					(size 1.27 1.27)
					(thickness 0.15)
				)
				(justify left bottom)
				(hide yes)
			)
		)
		(property "Datasheet" "https://www.bourns.com/docs/product-datasheets/cr.pdf"
			(at 171.45 256.54 0)
			(effects
				(font
					(size 1.27 1.27)
					(thickness 0.15)
				)
				(justify left bottom)
				(hide yes)
			)
		)
		(property "Description" ""
			(at 189.23 276.86 0)
			(effects
				(font
					(size 1.27 1.27)
				)
				(hide yes)
			)
		)
		(property "MPN" "CR0402-FX-2201GLF"
			(at 168.91 256.54 0)
			(effects
				(font
					(size 1.27 1.27)
					(thickness 0.15)
				)
				(justify left bottom)
				(hide yes)
			)
		)
		(property "Manufacturer" "Bourns"
			(at 166.37 256.54 0)
			(effects
				(font
					(size 1.27 1.27)
					(thickness 0.15)
				)
				(justify left bottom)
				(hide yes)
			)
		)
		(property "License" "Apache-2.0"
			(at 163.83 256.54 0)
			(effects
				(font
					(size 1.27 1.27)
					(thickness 0.15)
				)
				(justify left bottom)
				(hide yes)
			)
		)
		(property "Author" "Antmicro"
			(at 161.29 256.54 0)
			(effects
				(font
					(size 1.27 1.27)
					(thickness 0.15)
				)
				(justify left bottom)
				(hide yes)
			)
		)
		(property "Val" "2k2"
			(at 187.96 275.59 90)
			(effects
				(font
					(size 1.27 1.27)
					(thickness 0.15)
				)
				(justify right)
			)
		)
		(property "Tolerance" "1%"
			(at 179.07 256.54 0)
			(effects
				(font
					(size 1.27 1.27)
				)
				(justify left bottom)
				(hide yes)
			)
		)
		(pin "1"
		)
		(pin "2"
		)
		(instances
			(project "cm4-baseboard"
				(path ""
					(reference "R241")
					(unit 1)
				)
			)
		)
	)
	(symbol
		(lib_id "antmicropower:+3V3")
		(at 227.33 190.5 0)
		(unit 1)
		(exclude_from_sim no)
		(in_bom yes)
		(on_board yes)
		(dnp no)
		(property "Reference" "#PWR0210"
			(at 242.57 190.5 0)
			(effects
				(font
					(size 1.27 1.27)
					(thickness 0.15)
				)
				(justify left bottom)
				(hide yes)
			)
		)
		(property "Value" "+3V3"
			(at 227.33 186.69 0)
			(effects
				(font
					(size 1.27 1.27)
					(thickness 0.15)
				)
			)
		)
		(property "Footprint" ""
			(at 242.57 198.12 0)
			(effects
				(font
					(size 1.27 1.27)
					(thickness 0.15)
				)
				(justify left bottom)
				(hide yes)
			)
		)
		(property "Datasheet" ""
			(at 242.57 200.66 0)
			(effects
				(font
					(size 1.27 1.27)
					(thickness 0.15)
				)
				(justify left bottom)
				(hide yes)
			)
		)
		(property "Description" ""
			(at 227.33 190.5 0)
			(effects
				(font
					(size 1.27 1.27)
				)
				(hide yes)
			)
		)
		(property "Author" "Antmicro"
			(at 242.57 193.04 0)
			(effects
				(font
					(size 1.27 1.27)
					(thickness 0.15)
				)
				(justify left bottom)
				(hide yes)
			)
		)
		(property "License" "Apache-2.0"
			(at 242.57 195.58 0)
			(effects
				(font
					(size 1.27 1.27)
					(thickness 0.15)
				)
				(justify left bottom)
				(hide yes)
			)
		)
		(pin "1"
		)
		(instances
			(project "cm4-baseboard"
				(path ""
					(reference "#PWR0210")
					(unit 1)
				)
			)
		)
	)
	(symbol
		(lib_id "antmicroResistors0402:R_10k_0402")
		(at 260.35 256.54 270)
		(unit 1)
		(exclude_from_sim no)
		(in_bom yes)
		(on_board yes)
		(dnp no)
		(property "Reference" "R238"
			(at 261.62 259.08 90)
			(effects
				(font
					(size 1.27 1.27)
					(thickness 0.15)
				)
				(justify left bottom)
			)
		)
		(property "Value" "R_10k_0402"
			(at 247.65 276.86 0)
			(effects
				(font
					(size 1.27 1.27)
					(thickness 0.15)
				)
				(justify left bottom)
				(hide yes)
			)
		)
		(property "Footprint" "antmicro-footprints:R_0402_1005Metric"
			(at 245.11 276.86 0)
			(effects
				(font
					(size 1.27 1.27)
					(thickness 0.15)
				)
				(justify left bottom)
				(hide yes)
			)
		)
		(property "Datasheet" "https://www.bourns.com/docs/product-datasheets/cr.pdf"
			(at 242.57 276.86 0)
			(effects
				(font
					(size 1.27 1.27)
					(thickness 0.15)
				)
				(justify left bottom)
				(hide yes)
			)
		)
		(property "Description" ""
			(at 260.35 256.54 0)
			(effects
				(font
					(size 1.27 1.27)
				)
				(hide yes)
			)
		)
		(property "Manufacturer" "Bourns"
			(at 237.49 276.86 0)
			(effects
				(font
					(size 1.27 1.27)
					(thickness 0.15)
				)
				(justify left bottom)
				(hide yes)
			)
		)
		(property "MPN" "CR0402-FX-1002GLF"
			(at 240.03 276.86 0)
			(effects
				(font
					(size 1.27 1.27)
					(thickness 0.15)
				)
				(justify left bottom)
				(hide yes)
			)
		)
		(property "Val" "10k"
			(at 261.62 261.62 90)
			(effects
				(font
					(size 1.27 1.27)
					(thickness 0.15)
				)
				(justify left bottom)
			)
		)
		(property "License" "Apache-2.0"
			(at 234.95 276.86 0)
			(effects
				(font
					(size 1.27 1.27)
					(thickness 0.15)
				)
				(justify left bottom)
				(hide yes)
			)
		)
		(property "Author" "Antmicro"
			(at 232.41 276.86 0)
			(effects
				(font
					(size 1.27 1.27)
					(thickness 0.15)
				)
				(justify left bottom)
				(hide yes)
			)
		)
		(property "Tolerance" "1%"
			(at 250.19 276.86 0)
			(effects
				(font
					(size 1.27 1.27)
				)
				(justify left bottom)
				(hide yes)
			)
		)
		(pin "1"
		)
		(pin "2"
		)
		(instances
			(project "cm4-baseboard"
				(path ""
					(reference "R238")
					(unit 1)
				)
			)
		)
	)
	(symbol
		(lib_id "antmicroResistors0402:R_10k_0402")
		(at 248.92 44.45 90)
		(unit 1)
		(exclude_from_sim no)
		(in_bom yes)
		(on_board yes)
		(dnp no)
		(fields_autoplaced yes)
		(property "Reference" "R234"
			(at 246.38 40.6399 90)
			(effects
				(font
					(size 1.27 1.27)
					(thickness 0.15)
				)
				(justify left)
			)
		)
		(property "Value" "R_10k_0402"
			(at 261.62 24.13 0)
			(effects
				(font
					(size 1.27 1.27)
					(thickness 0.15)
				)
				(justify left bottom)
				(hide yes)
			)
		)
		(property "Footprint" "antmicro-footprints:R_0402_1005Metric"
			(at 264.16 24.13 0)
			(effects
				(font
					(size 1.27 1.27)
					(thickness 0.15)
				)
				(justify left bottom)
				(hide yes)
			)
		)
		(property "Datasheet" "https://www.bourns.com/docs/product-datasheets/cr.pdf"
			(at 266.7 24.13 0)
			(effects
				(font
					(size 1.27 1.27)
					(thickness 0.15)
				)
				(justify left bottom)
				(hide yes)
			)
		)
		(property "Description" ""
			(at 248.92 44.45 0)
			(effects
				(font
					(size 1.27 1.27)
				)
				(hide yes)
			)
		)
		(property "MPN" "CR0402-FX-1002GLF"
			(at 269.24 24.13 0)
			(effects
				(font
					(size 1.27 1.27)
					(thickness 0.15)
				)
				(justify left bottom)
				(hide yes)
			)
		)
		(property "Manufacturer" "Bourns"
			(at 271.78 24.13 0)
			(effects
				(font
					(size 1.27 1.27)
					(thickness 0.15)
				)
				(justify left bottom)
				(hide yes)
			)
		)
		(property "License" "Apache-2.0"
			(at 274.32 24.13 0)
			(effects
				(font
					(size 1.27 1.27)
					(thickness 0.15)
				)
				(justify left bottom)
				(hide yes)
			)
		)
		(property "Author" "Antmicro"
			(at 276.86 24.13 0)
			(effects
				(font
					(size 1.27 1.27)
					(thickness 0.15)
				)
				(justify left bottom)
				(hide yes)
			)
		)
		(property "Val" "10k"
			(at 246.38 43.1799 90)
			(effects
				(font
					(size 1.27 1.27)
					(thickness 0.15)
				)
				(justify left)
			)
		)
		(property "Tolerance" "1%"
			(at 259.08 24.13 0)
			(effects
				(font
					(size 1.27 1.27)
				)
				(justify left bottom)
				(hide yes)
			)
		)
		(pin "1"
		)
		(pin "2"
		)
		(instances
			(project "cm4-baseboard"
				(path ""
					(reference "R234")
					(unit 1)
				)
			)
		)
	)
	(symbol
		(lib_id "antmicroLEDIndicationDiscrete:LED_G_0603_KP-1608CGCK")
		(at 196.85 199.39 270)
		(mirror x)
		(unit 1)
		(exclude_from_sim no)
		(in_bom yes)
		(on_board yes)
		(dnp no)
		(property "Reference" "D206"
			(at 191.77 194.31 90)
			(effects
				(font
					(size 1.27 1.27)
					(thickness 0.15)
				)
			)
		)
		(property "Value" "LED_G_0603_KP-1608CGCK"
			(at 189.23 176.53 0)
			(effects
				(font
					(size 1.27 1.27)
					(thickness 0.15)
				)
				(justify left bottom)
				(hide yes)
			)
		)
		(property "Footprint" "antmicro-footprints:LED_0603_1608Metric_G"
			(at 186.69 176.53 0)
			(effects
				(font
					(size 1.27 1.27)
					(thickness 0.15)
				)
				(justify left bottom)
				(hide yes)
			)
		)
		(property "Datasheet" "http://www.kingbright.com/attachments/file/psearch//000/00/00/KP-1608CGCK(Ver.23B).pdf"
			(at 184.15 176.53 0)
			(effects
				(font
					(size 1.27 1.27)
					(thickness 0.15)
				)
				(justify left bottom)
				(hide yes)
			)
		)
		(property "Description" ""
			(at 196.85 199.39 0)
			(effects
				(font
					(size 1.27 1.27)
				)
				(hide yes)
			)
		)
		(property "MPN" "KP-1608CGCK"
			(at 181.61 176.53 0)
			(effects
				(font
					(size 1.27 1.27)
					(thickness 0.15)
				)
				(justify left bottom)
				(hide yes)
			)
		)
		(property "Manufacturer" "Kingbright"
			(at 179.07 176.53 0)
			(effects
				(font
					(size 1.27 1.27)
					(thickness 0.15)
				)
				(justify left bottom)
				(hide yes)
			)
		)
		(property "Color" "Green"
			(at 191.77 196.85 90)
			(effects
				(font
					(size 1.27 1.27)
				)
			)
		)
		(property "Author" "Antmicro"
			(at 176.53 176.53 0)
			(effects
				(font
					(size 1.27 1.27)
					(thickness 0.15)
				)
				(justify left bottom)
				(hide yes)
			)
		)
		(property "License" "Apache-2.0"
			(at 173.99 176.53 0)
			(effects
				(font
					(size 1.27 1.27)
					(thickness 0.15)
				)
				(justify left bottom)
				(hide yes)
			)
		)
		(pin "2"
		)
		(pin "1"
		)
		(instances
			(project "cm4-baseboard"
				(path ""
					(reference "D206")
					(unit 1)
				)
			)
		)
	)
	(symbol
		(lib_id "antmicropower:+3V3")
		(at 255.27 55.88 0)
		(unit 1)
		(exclude_from_sim no)
		(in_bom yes)
		(on_board yes)
		(dnp no)
		(property "Reference" "#PWR0240"
			(at 270.51 55.88 0)
			(effects
				(font
					(size 1.27 1.27)
					(thickness 0.15)
				)
				(justify left bottom)
				(hide yes)
			)
		)
		(property "Value" "+3V3"
			(at 252.73 52.07 0)
			(effects
				(font
					(size 1.27 1.27)
					(thickness 0.15)
				)
				(justify left)
			)
		)
		(property "Footprint" ""
			(at 270.51 63.5 0)
			(effects
				(font
					(size 1.27 1.27)
					(thickness 0.15)
				)
				(justify left bottom)
				(hide yes)
			)
		)
		(property "Datasheet" ""
			(at 270.51 66.04 0)
			(effects
				(font
					(size 1.27 1.27)
					(thickness 0.15)
				)
				(justify left bottom)
				(hide yes)
			)
		)
		(property "Description" ""
			(at 255.27 55.88 0)
			(effects
				(font
					(size 1.27 1.27)
				)
				(hide yes)
			)
		)
		(property "Author" "Antmicro"
			(at 270.51 58.42 0)
			(effects
				(font
					(size 1.27 1.27)
					(thickness 0.15)
				)
				(justify left bottom)
				(hide yes)
			)
		)
		(property "License" "Apache-2.0"
			(at 270.51 60.96 0)
			(effects
				(font
					(size 1.27 1.27)
					(thickness 0.15)
				)
				(justify left bottom)
				(hide yes)
			)
		)
		(pin "1"
		)
		(instances
			(project "cm4-baseboard"
				(path ""
					(reference "#PWR0240")
					(unit 1)
				)
			)
		)
	)
	(symbol
		(lib_id "antmicroTransistorsFETsMOSFETsSingle:SSM3J332R")
		(at 44.45 215.9 270)
		(mirror x)
		(unit 1)
		(exclude_from_sim no)
		(in_bom yes)
		(on_board yes)
		(dnp no)
		(property "Reference" "Q203"
			(at 53.34 212.09 90)
			(effects
				(font
					(size 1.27 1.27)
					(thickness 0.15)
				)
			)
		)
		(property "Value" "SSM3J332R"
			(at 53.34 214.63 90)
			(effects
				(font
					(size 1.27 1.27)
					(thickness 0.15)
				)
				(hide yes)
			)
		)
		(property "Footprint" "antmicro-footprints:SOT-23-3"
			(at 39.37 201.93 0)
			(effects
				(font
					(size 1.27 1.27)
					(thickness 0.15)
				)
				(justify left bottom)
				(hide yes)
			)
		)
		(property "Datasheet" "https://www.mouser.com/datasheet/2/408/SSM3J332R_datasheet_en_20181015-1150575.pdf"
			(at 36.83 201.93 0)
			(effects
				(font
					(size 1.27 1.27)
					(thickness 0.15)
				)
				(justify left bottom)
				(hide yes)
			)
		)
		(property "Description" ""
			(at 44.45 215.9 0)
			(effects
				(font
					(size 1.27 1.27)
				)
				(hide yes)
			)
		)
		(property "MPN" "SSM3J332R,LF"
			(at 46.99 214.63 90)
			(effects
				(font
					(size 1.27 1.27)
					(thickness 0.15)
				)
				(justify left bottom)
			)
		)
		(property "Manufacturer" "Toshiba"
			(at 31.75 201.93 0)
			(effects
				(font
					(size 1.27 1.27)
					(thickness 0.15)
				)
				(justify left bottom)
				(hide yes)
			)
		)
		(property "Author" "Antmicro"
			(at 29.21 201.93 0)
			(effects
				(font
					(size 1.27 1.27)
					(thickness 0.15)
				)
				(justify left bottom)
				(hide yes)
			)
		)
		(property "License" "Apache-2.0"
			(at 26.67 201.93 0)
			(effects
				(font
					(size 1.27 1.27)
					(thickness 0.15)
				)
				(justify left bottom)
				(hide yes)
			)
		)
		(pin "1"
		)
		(pin "2"
		)
		(pin "3"
		)
		(instances
			(project "cm4-baseboard"
				(path ""
					(reference "Q203")
					(unit 1)
				)
			)
		)
	)
	(symbol
		(lib_id "antmicroTVSDiodes:TPD1E0B04_XDFN-2")
		(at 114.3 245.11 90)
		(unit 1)
		(exclude_from_sim no)
		(in_bom yes)
		(on_board yes)
		(dnp no)
		(fields_autoplaced yes)
		(property "Reference" "D204"
			(at 111.76 241.2999 90)
			(effects
				(font
					(size 1.27 1.27)
				)
				(justify left)
			)
		)
		(property "Value" "TPD1E0B04_XDFN-2"
			(at 111.76 243.8399 90)
			(effects
				(font
					(size 1.27 1.27)
				)
				(justify left)
			)
		)
		(property "Footprint" "antmicro-footprints:XDFN-2_1x0.60mm"
			(at 109.22 240.03 0)
			(effects
				(font
					(size 1.524 1.524)
				)
				(justify left bottom)
				(hide yes)
			)
		)
		(property "Datasheet" "https://www.ti.com/general/docs/suppproductinfo.tsp?distId=26&gotoUrl=https://www.ti.com/lit/gpn/tpd1e0b04"
			(at 106.68 240.03 0)
			(effects
				(font
					(size 1.524 1.524)
				)
				(justify left bottom)
				(hide yes)
			)
		)
		(property "Description" ""
			(at 114.3 245.11 0)
			(effects
				(font
					(size 1.27 1.27)
				)
				(hide yes)
			)
		)
		(property "Manufacturer" "Texas Instruments"
			(at 86.36 240.03 0)
			(effects
				(font
					(size 1.524 1.524)
				)
				(justify left bottom)
				(hide yes)
			)
		)
		(property "MPN" "TPD1E0B04DPYR"
			(at 101.6 240.03 0)
			(effects
				(font
					(size 1.524 1.524)
				)
				(justify left bottom)
				(hide yes)
			)
		)
		(property "Author" "Antmicro"
			(at 129.54 229.87 0)
			(effects
				(font
					(size 1.27 1.27)
					(thickness 0.15)
				)
				(justify left bottom)
				(hide yes)
			)
		)
		(property "License" "Apache-2.0"
			(at 132.08 229.87 0)
			(effects
				(font
					(size 1.27 1.27)
					(thickness 0.15)
				)
				(justify left bottom)
				(hide yes)
			)
		)
		(pin "1"
		)
		(pin "2"
		)
		(instances
			(project "cm4-baseboard"
				(path ""
					(reference "D204")
					(unit 1)
				)
			)
		)
	)
	(symbol
		(lib_id "antmicropower:GND")
		(at 134.62 246.38 0)
		(unit 1)
		(exclude_from_sim no)
		(in_bom yes)
		(on_board yes)
		(dnp no)
		(property "Reference" "#PWR0219"
			(at 134.62 252.73 0)
			(effects
				(font
					(size 1.27 1.27)
				)
				(justify left bottom)
				(hide yes)
			)
		)
		(property "Value" "GND"
			(at 134.62 250.19 0)
			(effects
				(font
					(size 1.27 1.27)
				)
			)
		)
		(property "Footprint" ""
			(at 143.51 254 0)
			(effects
				(font
					(size 1.27 1.27)
					(thickness 0.15)
				)
				(justify left bottom)
				(hide yes)
			)
		)
		(property "Datasheet" ""
			(at 143.51 259.08 0)
			(effects
				(font
					(size 1.27 1.27)
					(thickness 0.15)
				)
				(justify left bottom)
				(hide yes)
			)
		)
		(property "Description" ""
			(at 134.62 246.38 0)
			(effects
				(font
					(size 1.27 1.27)
				)
				(hide yes)
			)
		)
		(property "Author" "Antmicro"
			(at 143.51 254 0)
			(effects
				(font
					(size 1.27 1.27)
					(thickness 0.15)
				)
				(justify left bottom)
				(hide yes)
			)
		)
		(property "License" "Apache-2.0"
			(at 143.51 256.54 0)
			(effects
				(font
					(size 1.27 1.27)
					(thickness 0.15)
				)
				(justify left bottom)
				(hide yes)
			)
		)
		(pin "1"
		)
		(instances
			(project "cm4-baseboard"
				(path ""
					(reference "#PWR0219")
					(unit 1)
				)
			)
		)
	)
	(symbol
		(lib_id "antmicroResistors0402:R_0R_0402")
		(at 196.85 107.95 0)
		(unit 1)
		(exclude_from_sim no)
		(in_bom yes)
		(on_board yes)
		(dnp no)
		(property "Reference" "R226"
			(at 194.31 106.68 0)
			(effects
				(font
					(size 1.27 1.27)
				)
			)
		)
		(property "Value" "R_0R_0402"
			(at 196.85 111.76 0)
			(effects
				(font
					(size 1.27 1.27)
				)
				(justify left bottom)
				(hide yes)
			)
		)
		(property "Footprint" "antmicro-footprints:R_0402_1005Metric"
			(at 201.93 102.87 0)
			(effects
				(font
					(size 1.524 1.524)
				)
				(justify left bottom)
				(hide yes)
			)
		)
		(property "Datasheet" "https://industrial.panasonic.com/cdbs/www-data/pdf/RDA0000/AOA0000C301.pdf"
			(at 196.85 107.95 0)
			(effects
				(font
					(size 1.27 1.27)
				)
				(justify left bottom)
				(hide yes)
			)
		)
		(property "Description" ""
			(at 196.85 107.95 0)
			(effects
				(font
					(size 1.27 1.27)
				)
				(hide yes)
			)
		)
		(property "Manufacturer" "Panasonic"
			(at 201.93 97.79 0)
			(effects
				(font
					(size 1.524 1.524)
				)
				(justify left bottom)
				(hide yes)
			)
		)
		(property "MPN" "ERJ2GE0R00X"
			(at 201.93 100.33 0)
			(effects
				(font
					(size 1.524 1.524)
				)
				(justify left bottom)
				(hide yes)
			)
		)
		(property "Val" "0R"
			(at 203.2 106.68 0)
			(effects
				(font
					(size 1.27 1.27)
				)
			)
		)
		(property "License" "Apache-2.0"
			(at 217.17 133.35 0)
			(effects
				(font
					(size 1.27 1.27)
					(thickness 0.15)
				)
				(justify left bottom)
				(hide yes)
			)
		)
		(property "Author" "Antmicro"
			(at 217.17 135.89 0)
			(effects
				(font
					(size 1.27 1.27)
					(thickness 0.15)
				)
				(justify left bottom)
				(hide yes)
			)
		)
		(property "Tolerance" "~"
			(at 217.17 118.11 0)
			(effects
				(font
					(size 1.27 1.27)
				)
				(justify left bottom)
				(hide yes)
			)
		)
		(property "Current" "1A"
			(at 199.39 106.045 0)
			(effects
				(font
					(size 1.27 1.27)
					(thickness 0.15)
				)
				(hide yes)
			)
		)
		(pin "1"
		)
		(pin "2"
		)
		(instances
			(project "cm4-baseboard"
				(path ""
					(reference "R226")
					(unit 1)
				)
			)
		)
	)
	(symbol
		(lib_id "antmicroTestPoints:TP_0.75mm_SMD")
		(at 196.85 46.99 0)
		(mirror x)
		(unit 1)
		(exclude_from_sim no)
		(in_bom no)
		(on_board yes)
		(dnp no)
		(property "Reference" "TP212"
			(at 204.47 46.99 0)
			(effects
				(font
					(size 1.27 1.27)
					(thickness 0.15)
				)
			)
		)
		(property "Value" "TP_0.75mm_SMD"
			(at 212.09 39.37 0)
			(effects
				(font
					(size 1.27 1.27)
					(thickness 0.15)
				)
				(justify left bottom)
				(hide yes)
			)
		)
		(property "Footprint" "antmicro-footprints:TP_SMD_0.75mm"
			(at 207.645 40.64 0)
			(effects
				(font
					(size 1.27 1.27)
					(thickness 0.15)
				)
				(justify left bottom)
				(hide yes)
			)
		)
		(property "Datasheet" ""
			(at 214.63 34.29 0)
			(effects
				(font
					(size 1.27 1.27)
					(thickness 0.15)
				)
				(justify left bottom)
				(hide yes)
			)
		)
		(property "Description" ""
			(at 196.85 46.99 0)
			(effects
				(font
					(size 1.27 1.27)
				)
				(hide yes)
			)
		)
		(property "Author" "Antmicro"
			(at 207.645 38.1 0)
			(effects
				(font
					(size 1.27 1.27)
					(thickness 0.15)
				)
				(justify left bottom)
				(hide yes)
			)
		)
		(property "License" "Apache-2.0"
			(at 207.645 35.56 0)
			(effects
				(font
					(size 1.27 1.27)
					(thickness 0.15)
				)
				(justify left bottom)
				(hide yes)
			)
		)
		(property "MPN" ""
			(at 207.645 35.56 0)
			(effects
				(font
					(size 1.27 1.27)
					(thickness 0.15)
				)
				(justify left bottom)
				(hide yes)
			)
		)
		(property "Manufacturer" ""
			(at 207.645 40.64 0)
			(effects
				(font
					(size 1.27 1.27)
					(thickness 0.15)
				)
				(justify left bottom)
				(hide yes)
			)
		)
		(pin "1"
		)
		(instances
			(project "cm4-baseboard"
				(path ""
					(reference "TP212")
					(unit 1)
				)
			)
		)
	)
	(symbol
		(lib_id "antmicropower:PWR_FLAG")
		(at 21.59 142.24 0)
		(unit 1)
		(exclude_from_sim no)
		(in_bom yes)
		(on_board yes)
		(dnp no)
		(property "Reference" "#FLG02"
			(at 21.59 140.335 0)
			(effects
				(font
					(size 1.27 1.27)
				)
				(hide yes)
			)
		)
		(property "Value" "PWR_FLAG"
			(at 21.59 138.43 0)
			(effects
				(font
					(size 1.27 1.27)
				)
			)
		)
		(property "Footprint" ""
			(at 21.59 142.24 0)
			(effects
				(font
					(size 1.27 1.27)
				)
				(hide yes)
			)
		)
		(property "Datasheet" ""
			(at 21.59 142.24 0)
			(effects
				(font
					(size 1.27 1.27)
				)
				(hide yes)
			)
		)
		(property "Description" ""
			(at 21.59 142.24 0)
			(effects
				(font
					(size 1.27 1.27)
				)
				(hide yes)
			)
		)
		(pin "1"
		)
		(instances
			(project "cm4-baseboard"
				(path ""
					(reference "#FLG02")
					(unit 1)
				)
			)
		)
	)
	(symbol
		(lib_id "antmicropower:+5V")
		(at 100.33 58.42 0)
		(unit 1)
		(exclude_from_sim no)
		(in_bom yes)
		(on_board yes)
		(dnp no)
		(property "Reference" "#PWR0209"
			(at 115.57 60.96 0)
			(effects
				(font
					(size 1.27 1.27)
					(thickness 0.15)
				)
				(justify left bottom)
				(hide yes)
			)
		)
		(property "Value" "+5V"
			(at 100.33 54.61 0)
			(effects
				(font
					(size 1.27 1.27)
					(thickness 0.15)
				)
			)
		)
		(property "Footprint" ""
			(at 115.57 66.04 0)
			(effects
				(font
					(size 1.27 1.27)
					(thickness 0.15)
				)
				(justify left bottom)
				(hide yes)
			)
		)
		(property "Datasheet" ""
			(at 115.57 68.58 0)
			(effects
				(font
					(size 1.27 1.27)
					(thickness 0.15)
				)
				(justify left bottom)
				(hide yes)
			)
		)
		(property "Description" ""
			(at 100.33 58.42 0)
			(effects
				(font
					(size 1.27 1.27)
				)
				(hide yes)
			)
		)
		(property "Author" "Antmicro"
			(at 115.57 66.04 0)
			(effects
				(font
					(size 1.27 1.27)
					(thickness 0.15)
				)
				(justify left bottom)
				(hide yes)
			)
		)
		(property "License" "Apache-2.0"
			(at 115.57 68.58 0)
			(effects
				(font
					(size 1.27 1.27)
					(thickness 0.15)
				)
				(justify left bottom)
				(hide yes)
			)
		)
		(pin "1"
		)
		(instances
			(project "cm4-baseboard"
				(path ""
					(reference "#PWR0209")
					(unit 1)
				)
			)
		)
	)
	(symbol
		(lib_id "antmicroTestPoints:TP_0.75mm_SMD")
		(at 68.58 210.82 270)
		(unit 1)
		(exclude_from_sim no)
		(in_bom no)
		(on_board yes)
		(dnp no)
		(property "Reference" "TP215"
			(at 71.12 216.535 90)
			(effects
				(font
					(size 1.27 1.27)
				)
				(justify right)
			)
		)
		(property "Value" "TP_0.75mm_SMD"
			(at 66.04 210.82 0)
			(effects
				(font
					(size 1.27 1.27)
					(thickness 0.15)
				)
				(justify left bottom)
				(hide yes)
			)
		)
		(property "Footprint" "antmicro-footprints:TP_SMD_0.75mm"
			(at 73.66 215.9 0)
			(effects
				(font
					(size 1.27 1.27)
					(thickness 0.15)
				)
				(justify left bottom)
				(hide yes)
			)
		)
		(property "Datasheet" ""
			(at 76.2 215.9 0)
			(effects
				(font
					(size 1.27 1.27)
					(thickness 0.15)
				)
				(justify left bottom)
				(hide yes)
			)
		)
		(property "Description" ""
			(at 68.58 210.82 0)
			(effects
				(font
					(size 1.27 1.27)
				)
				(hide yes)
			)
		)
		(property "MPN" ""
			(at 68.58 210.82 0)
			(effects
				(font
					(size 1.27 1.27)
					(thickness 0.15)
				)
				(justify left bottom)
				(hide yes)
			)
		)
		(property "Manufacturer" ""
			(at 68.58 210.82 0)
			(effects
				(font
					(size 1.27 1.27)
					(thickness 0.15)
				)
				(justify left bottom)
				(hide yes)
			)
		)
		(property "Author" "Antmicro"
			(at 53.34 226.06 0)
			(effects
				(font
					(size 1.27 1.27)
					(thickness 0.15)
				)
				(justify left bottom)
				(hide yes)
			)
		)
		(property "License" "Apache-2.0"
			(at 50.8 226.06 0)
			(effects
				(font
					(size 1.27 1.27)
					(thickness 0.15)
				)
				(justify left bottom)
				(hide yes)
			)
		)
		(pin "1"
		)
		(instances
			(project "cm4-baseboard"
				(path ""
					(reference "TP215")
					(unit 1)
				)
			)
		)
	)
	(symbol
		(lib_id "antmicroResistors0402:R_100k_0402")
		(at 350.52 226.06 90)
		(unit 1)
		(exclude_from_sim no)
		(in_bom yes)
		(on_board yes)
		(dnp no)
		(fields_autoplaced yes)
		(property "Reference" "R261"
			(at 347.98 222.25 90)
			(effects
				(font
					(size 1.27 1.27)
					(thickness 0.15)
				)
				(justify left)
			)
		)
		(property "Value" "R_100k_0402"
			(at 363.22 205.74 0)
			(effects
				(font
					(size 1.27 1.27)
					(thickness 0.15)
				)
				(justify left bottom)
				(hide yes)
			)
		)
		(property "Footprint" "antmicro-footprints:R_0402_1005Metric"
			(at 365.76 205.74 0)
			(effects
				(font
					(size 1.27 1.27)
					(thickness 0.15)
				)
				(justify left bottom)
				(hide yes)
			)
		)
		(property "Datasheet" "https://www.bourns.com/docs/product-datasheets/cr.pdf"
			(at 368.3 205.74 0)
			(effects
				(font
					(size 1.27 1.27)
					(thickness 0.15)
				)
				(justify left bottom)
				(hide yes)
			)
		)
		(property "Description" ""
			(at 350.52 226.06 0)
			(effects
				(font
					(size 1.27 1.27)
				)
				(hide yes)
			)
		)
		(property "MPN" "CR0402-FX-1003GLF"
			(at 370.84 205.74 0)
			(effects
				(font
					(size 1.27 1.27)
					(thickness 0.15)
				)
				(justify left bottom)
				(hide yes)
			)
		)
		(property "Manufacturer" "Bourns"
			(at 373.38 205.74 0)
			(effects
				(font
					(size 1.27 1.27)
					(thickness 0.15)
				)
				(justify left bottom)
				(hide yes)
			)
		)
		(property "License" "Apache-2.0"
			(at 375.92 205.74 0)
			(effects
				(font
					(size 1.27 1.27)
					(thickness 0.15)
				)
				(justify left bottom)
				(hide yes)
			)
		)
		(property "Author" "Antmicro"
			(at 378.46 205.74 0)
			(effects
				(font
					(size 1.27 1.27)
					(thickness 0.15)
				)
				(justify left bottom)
				(hide yes)
			)
		)
		(property "Val" "100k"
			(at 347.98 224.79 90)
			(effects
				(font
					(size 1.27 1.27)
					(thickness 0.15)
				)
				(justify left)
			)
		)
		(property "Tolerance" "1%"
			(at 360.68 205.74 0)
			(effects
				(font
					(size 1.27 1.27)
				)
				(justify left bottom)
				(hide yes)
			)
		)
		(pin "1"
		)
		(pin "2"
		)
		(instances
			(project "cm4-baseboard"
				(path ""
					(reference "R261")
					(unit 1)
				)
			)
		)
	)
	(symbol
		(lib_id "antmicroResistors0402:R_0R_0402")
		(at 26.67 146.05 0)
		(unit 1)
		(exclude_from_sim no)
		(in_bom no)
		(on_board yes)
		(dnp yes)
		(property "Reference" "R202"
			(at 29.21 148.59 0)
			(effects
				(font
					(size 1.27 1.27)
				)
			)
		)
		(property "Value" "R_0R_0402"
			(at 26.67 149.86 0)
			(effects
				(font
					(size 1.27 1.27)
				)
				(justify left bottom)
				(hide yes)
			)
		)
		(property "Footprint" "antmicro-footprints:R_0402_1005Metric"
			(at 31.75 140.97 0)
			(effects
				(font
					(size 1.524 1.524)
				)
				(justify left bottom)
				(hide yes)
			)
		)
		(property "Datasheet" "https://industrial.panasonic.com/cdbs/www-data/pdf/RDA0000/AOA0000C301.pdf"
			(at 26.67 146.05 0)
			(effects
				(font
					(size 1.27 1.27)
				)
				(justify left bottom)
				(hide yes)
			)
		)
		(property "Description" ""
			(at 26.67 146.05 0)
			(effects
				(font
					(size 1.27 1.27)
				)
				(hide yes)
			)
		)
		(property "Manufacturer" "Panasonic"
			(at 31.75 135.89 0)
			(effects
				(font
					(size 1.524 1.524)
				)
				(justify left bottom)
				(hide yes)
			)
		)
		(property "MPN" "ERJ2GE0R00X"
			(at 31.75 138.43 0)
			(effects
				(font
					(size 1.524 1.524)
				)
				(justify left bottom)
				(hide yes)
			)
		)
		(property "Val" "0R"
			(at 29.21 151.13 0)
			(effects
				(font
					(size 1.27 1.27)
				)
			)
		)
		(property "License" "Apache-2.0"
			(at 46.99 171.45 0)
			(effects
				(font
					(size 1.27 1.27)
					(thickness 0.15)
				)
				(justify left bottom)
				(hide yes)
			)
		)
		(property "Author" "Antmicro"
			(at 46.99 173.99 0)
			(effects
				(font
					(size 1.27 1.27)
					(thickness 0.15)
				)
				(justify left bottom)
				(hide yes)
			)
		)
		(property "Tolerance" "~"
			(at 46.99 156.21 0)
			(effects
				(font
					(size 1.27 1.27)
				)
				(justify left bottom)
				(hide yes)
			)
		)
		(property "Current" "1A"
			(at 29.21 144.145 0)
			(effects
				(font
					(size 1.27 1.27)
					(thickness 0.15)
				)
				(hide yes)
			)
		)
		(pin "1"
		)
		(pin "2"
		)
		(instances
			(project "cm4-baseboard"
				(path ""
					(reference "R202")
					(unit 1)
				)
			)
		)
	)
	(symbol
		(lib_id "antmicroResistors0402:R_1k_0402")
		(at 196.85 205.74 90)
		(unit 1)
		(exclude_from_sim no)
		(in_bom yes)
		(on_board yes)
		(dnp no)
		(property "Reference" "R229"
			(at 193.04 204.47 90)
			(effects
				(font
					(size 1.27 1.27)
					(thickness 0.15)
				)
			)
		)
		(property "Value" "R_1k_0402"
			(at 209.55 185.42 0)
			(effects
				(font
					(size 1.27 1.27)
					(thickness 0.15)
				)
				(justify left bottom)
				(hide yes)
			)
		)
		(property "Footprint" "antmicro-footprints:R_0402_1005Metric"
			(at 212.09 185.42 0)
			(effects
				(font
					(size 1.27 1.27)
					(thickness 0.15)
				)
				(justify left bottom)
				(hide yes)
			)
		)
		(property "Datasheet" "https://www.bourns.com/docs/product-datasheets/cr.pdf"
			(at 214.63 185.42 0)
			(effects
				(font
					(size 1.27 1.27)
					(thickness 0.15)
				)
				(justify left bottom)
				(hide yes)
			)
		)
		(property "Description" ""
			(at 196.85 205.74 0)
			(effects
				(font
					(size 1.27 1.27)
				)
				(hide yes)
			)
		)
		(property "MPN" "CR0402-FX-1001GLF"
			(at 217.17 185.42 0)
			(effects
				(font
					(size 1.27 1.27)
					(thickness 0.15)
				)
				(justify left bottom)
				(hide yes)
			)
		)
		(property "Manufacturer" "Bourns"
			(at 219.71 185.42 0)
			(effects
				(font
					(size 1.27 1.27)
					(thickness 0.15)
				)
				(justify left bottom)
				(hide yes)
			)
		)
		(property "License" "Apache-2.0"
			(at 222.25 185.42 0)
			(effects
				(font
					(size 1.27 1.27)
					(thickness 0.15)
				)
				(justify left bottom)
				(hide yes)
			)
		)
		(property "Author" "Antmicro"
			(at 224.79 185.42 0)
			(effects
				(font
					(size 1.27 1.27)
					(thickness 0.15)
				)
				(justify left bottom)
				(hide yes)
			)
		)
		(property "Val" "1k"
			(at 194.31 201.93 90)
			(effects
				(font
					(size 1.27 1.27)
					(thickness 0.15)
				)
			)
		)
		(property "Tolerance" "1%"
			(at 207.01 185.42 0)
			(effects
				(font
					(size 1.27 1.27)
				)
				(justify left bottom)
				(hide yes)
			)
		)
		(pin "1"
		)
		(pin "2"
		)
		(instances
			(project "cm4-baseboard"
				(path ""
					(reference "R229")
					(unit 1)
				)
			)
		)
	)
	(symbol
		(lib_id "antmicroTransistorsFETsMOSFETsSingle:SSM3J332R")
		(at 44.45 238.76 270)
		(mirror x)
		(unit 1)
		(exclude_from_sim no)
		(in_bom yes)
		(on_board yes)
		(dnp no)
		(property "Reference" "Q205"
			(at 53.34 234.95 90)
			(effects
				(font
					(size 1.27 1.27)
					(thickness 0.15)
				)
			)
		)
		(property "Value" "SSM3J332R"
			(at 53.34 237.49 90)
			(effects
				(font
					(size 1.27 1.27)
					(thickness 0.15)
				)
				(hide yes)
			)
		)
		(property "Footprint" "antmicro-footprints:SOT-23-3"
			(at 39.37 224.79 0)
			(effects
				(font
					(size 1.27 1.27)
					(thickness 0.15)
				)
				(justify left bottom)
				(hide yes)
			)
		)
		(property "Datasheet" "https://www.mouser.com/datasheet/2/408/SSM3J332R_datasheet_en_20181015-1150575.pdf"
			(at 36.83 224.79 0)
			(effects
				(font
					(size 1.27 1.27)
					(thickness 0.15)
				)
				(justify left bottom)
				(hide yes)
			)
		)
		(property "Description" ""
			(at 44.45 238.76 0)
			(effects
				(font
					(size 1.27 1.27)
				)
				(hide yes)
			)
		)
		(property "MPN" "SSM3J332R,LF"
			(at 46.99 237.49 90)
			(effects
				(font
					(size 1.27 1.27)
					(thickness 0.15)
				)
				(justify left bottom)
			)
		)
		(property "Manufacturer" "Toshiba"
			(at 31.75 224.79 0)
			(effects
				(font
					(size 1.27 1.27)
					(thickness 0.15)
				)
				(justify left bottom)
				(hide yes)
			)
		)
		(property "Author" "Antmicro"
			(at 29.21 224.79 0)
			(effects
				(font
					(size 1.27 1.27)
					(thickness 0.15)
				)
				(justify left bottom)
				(hide yes)
			)
		)
		(property "License" "Apache-2.0"
			(at 26.67 224.79 0)
			(effects
				(font
					(size 1.27 1.27)
					(thickness 0.15)
				)
				(justify left bottom)
				(hide yes)
			)
		)
		(pin "1"
		)
		(pin "2"
		)
		(pin "3"
		)
		(instances
			(project "cm4-baseboard"
				(path ""
					(reference "Q205")
					(unit 1)
				)
			)
		)
	)
	(symbol
		(lib_id "antmicropower:GND")
		(at 255.27 196.85 0)
		(unit 1)
		(exclude_from_sim no)
		(in_bom yes)
		(on_board yes)
		(dnp no)
		(fields_autoplaced yes)
		(property "Reference" "#PWR0234"
			(at 264.16 199.39 0)
			(effects
				(font
					(size 1.27 1.27)
					(thickness 0.15)
				)
				(justify left bottom)
				(hide yes)
			)
		)
		(property "Value" "GND"
			(at 255.27 201.295 0)
			(effects
				(font
					(size 1.27 1.27)
					(thickness 0.15)
				)
			)
		)
		(property "Footprint" ""
			(at 264.16 204.47 0)
			(effects
				(font
					(size 1.27 1.27)
					(thickness 0.15)
				)
				(justify left bottom)
				(hide yes)
			)
		)
		(property "Datasheet" ""
			(at 264.16 209.55 0)
			(effects
				(font
					(size 1.27 1.27)
					(thickness 0.15)
				)
				(justify left bottom)
				(hide yes)
			)
		)
		(property "Description" ""
			(at 255.27 196.85 0)
			(effects
				(font
					(size 1.27 1.27)
				)
				(hide yes)
			)
		)
		(property "Author" "Antmicro"
			(at 264.16 204.47 0)
			(effects
				(font
					(size 1.27 1.27)
					(thickness 0.15)
				)
				(justify left bottom)
				(hide yes)
			)
		)
		(property "License" "Apache-2.0"
			(at 264.16 207.01 0)
			(effects
				(font
					(size 1.27 1.27)
					(thickness 0.15)
				)
				(justify left bottom)
				(hide yes)
			)
		)
		(pin "1"
		)
		(instances
			(project "cm4-baseboard"
				(path ""
					(reference "#PWR0234")
					(unit 1)
				)
			)
		)
	)
	(symbol
		(lib_id "antmicroResistors0402:R_0R_0402")
		(at 156.21 90.17 0)
		(unit 1)
		(exclude_from_sim no)
		(in_bom yes)
		(on_board yes)
		(dnp no)
		(property "Reference" "R216"
			(at 153.67 88.9 0)
			(effects
				(font
					(size 1.27 1.27)
				)
			)
		)
		(property "Value" "R_0R_0402"
			(at 156.21 93.98 0)
			(effects
				(font
					(size 1.27 1.27)
				)
				(justify left bottom)
				(hide yes)
			)
		)
		(property "Footprint" "antmicro-footprints:R_0402_1005Metric"
			(at 161.29 85.09 0)
			(effects
				(font
					(size 1.524 1.524)
				)
				(justify left bottom)
				(hide yes)
			)
		)
		(property "Datasheet" "https://industrial.panasonic.com/cdbs/www-data/pdf/RDA0000/AOA0000C301.pdf"
			(at 156.21 90.17 0)
			(effects
				(font
					(size 1.27 1.27)
				)
				(justify left bottom)
				(hide yes)
			)
		)
		(property "Description" ""
			(at 156.21 90.17 0)
			(effects
				(font
					(size 1.27 1.27)
				)
				(hide yes)
			)
		)
		(property "Manufacturer" "Panasonic"
			(at 161.29 80.01 0)
			(effects
				(font
					(size 1.524 1.524)
				)
				(justify left bottom)
				(hide yes)
			)
		)
		(property "MPN" "ERJ2GE0R00X"
			(at 161.29 82.55 0)
			(effects
				(font
					(size 1.524 1.524)
				)
				(justify left bottom)
				(hide yes)
			)
		)
		(property "Val" "0R"
			(at 162.56 88.9 0)
			(effects
				(font
					(size 1.27 1.27)
				)
			)
		)
		(property "License" "Apache-2.0"
			(at 176.53 115.57 0)
			(effects
				(font
					(size 1.27 1.27)
					(thickness 0.15)
				)
				(justify left bottom)
				(hide yes)
			)
		)
		(property "Author" "Antmicro"
			(at 176.53 118.11 0)
			(effects
				(font
					(size 1.27 1.27)
					(thickness 0.15)
				)
				(justify left bottom)
				(hide yes)
			)
		)
		(property "Tolerance" "~"
			(at 176.53 100.33 0)
			(effects
				(font
					(size 1.27 1.27)
				)
				(justify left bottom)
				(hide yes)
			)
		)
		(property "Current" "1A"
			(at 158.75 88.265 0)
			(effects
				(font
					(size 1.27 1.27)
					(thickness 0.15)
				)
				(hide yes)
			)
		)
		(pin "1"
		)
		(pin "2"
		)
		(instances
			(project "cm4-baseboard"
				(path ""
					(reference "R216")
					(unit 1)
				)
			)
		)
	)
	(symbol
		(lib_id "antmicroResistors0402:R_0R_0402")
		(at 156.21 115.57 0)
		(unit 1)
		(exclude_from_sim no)
		(in_bom yes)
		(on_board yes)
		(dnp no)
		(property "Reference" "R223"
			(at 153.67 114.3 0)
			(effects
				(font
					(size 1.27 1.27)
				)
			)
		)
		(property "Value" "R_0R_0402"
			(at 156.21 119.38 0)
			(effects
				(font
					(size 1.27 1.27)
				)
				(justify left bottom)
				(hide yes)
			)
		)
		(property "Footprint" "antmicro-footprints:R_0402_1005Metric"
			(at 161.29 110.49 0)
			(effects
				(font
					(size 1.524 1.524)
				)
				(justify left bottom)
				(hide yes)
			)
		)
		(property "Datasheet" "https://industrial.panasonic.com/cdbs/www-data/pdf/RDA0000/AOA0000C301.pdf"
			(at 156.21 115.57 0)
			(effects
				(font
					(size 1.27 1.27)
				)
				(justify left bottom)
				(hide yes)
			)
		)
		(property "Description" ""
			(at 156.21 115.57 0)
			(effects
				(font
					(size 1.27 1.27)
				)
				(hide yes)
			)
		)
		(property "Manufacturer" "Panasonic"
			(at 161.29 105.41 0)
			(effects
				(font
					(size 1.524 1.524)
				)
				(justify left bottom)
				(hide yes)
			)
		)
		(property "MPN" "ERJ2GE0R00X"
			(at 161.29 107.95 0)
			(effects
				(font
					(size 1.524 1.524)
				)
				(justify left bottom)
				(hide yes)
			)
		)
		(property "Val" "0R"
			(at 162.56 114.3 0)
			(effects
				(font
					(size 1.27 1.27)
				)
			)
		)
		(property "License" "Apache-2.0"
			(at 176.53 140.97 0)
			(effects
				(font
					(size 1.27 1.27)
					(thickness 0.15)
				)
				(justify left bottom)
				(hide yes)
			)
		)
		(property "Author" "Antmicro"
			(at 176.53 143.51 0)
			(effects
				(font
					(size 1.27 1.27)
					(thickness 0.15)
				)
				(justify left bottom)
				(hide yes)
			)
		)
		(property "Tolerance" "~"
			(at 176.53 125.73 0)
			(effects
				(font
					(size 1.27 1.27)
				)
				(justify left bottom)
				(hide yes)
			)
		)
		(property "Current" "1A"
			(at 158.75 113.665 0)
			(effects
				(font
					(size 1.27 1.27)
					(thickness 0.15)
				)
				(hide yes)
			)
		)
		(pin "1"
		)
		(pin "2"
		)
		(instances
			(project "cm4-baseboard"
				(path ""
					(reference "R223")
					(unit 1)
				)
			)
		)
	)
	(symbol
		(lib_id "antmicroResistors0402:R_0R_0402")
		(at 189.23 252.73 0)
		(unit 1)
		(exclude_from_sim no)
		(in_bom yes)
		(on_board yes)
		(dnp no)
		(property "Reference" "R239"
			(at 186.69 251.46 0)
			(effects
				(font
					(size 1.27 1.27)
				)
			)
		)
		(property "Value" "R_0R_0402"
			(at 189.23 256.54 0)
			(effects
				(font
					(size 1.27 1.27)
				)
				(justify left bottom)
				(hide yes)
			)
		)
		(property "Footprint" "antmicro-footprints:R_0402_1005Metric"
			(at 194.31 247.65 0)
			(effects
				(font
					(size 1.524 1.524)
				)
				(justify left bottom)
				(hide yes)
			)
		)
		(property "Datasheet" "https://industrial.panasonic.com/cdbs/www-data/pdf/RDA0000/AOA0000C301.pdf"
			(at 189.23 252.73 0)
			(effects
				(font
					(size 1.27 1.27)
				)
				(justify left bottom)
				(hide yes)
			)
		)
		(property "Description" ""
			(at 189.23 252.73 0)
			(effects
				(font
					(size 1.27 1.27)
				)
				(hide yes)
			)
		)
		(property "Manufacturer" "Panasonic"
			(at 194.31 242.57 0)
			(effects
				(font
					(size 1.524 1.524)
				)
				(justify left bottom)
				(hide yes)
			)
		)
		(property "MPN" "ERJ2GE0R00X"
			(at 194.31 245.11 0)
			(effects
				(font
					(size 1.524 1.524)
				)
				(justify left bottom)
				(hide yes)
			)
		)
		(property "Val" "0R"
			(at 195.58 251.46 0)
			(effects
				(font
					(size 1.27 1.27)
				)
			)
		)
		(property "License" "Apache-2.0"
			(at 209.55 278.13 0)
			(effects
				(font
					(size 1.27 1.27)
					(thickness 0.15)
				)
				(justify left bottom)
				(hide yes)
			)
		)
		(property "Author" "Antmicro"
			(at 209.55 280.67 0)
			(effects
				(font
					(size 1.27 1.27)
					(thickness 0.15)
				)
				(justify left bottom)
				(hide yes)
			)
		)
		(property "Tolerance" "~"
			(at 209.55 262.89 0)
			(effects
				(font
					(size 1.27 1.27)
				)
				(justify left bottom)
				(hide yes)
			)
		)
		(property "Current" "1A"
			(at 191.77 250.825 0)
			(effects
				(font
					(size 1.27 1.27)
					(thickness 0.15)
				)
				(hide yes)
			)
		)
		(pin "1"
		)
		(pin "2"
		)
		(instances
			(project "cm4-baseboard"
				(path ""
					(reference "R239")
					(unit 1)
				)
			)
		)
	)
	(symbol
		(lib_id "antmicropower:+3V3")
		(at 218.44 186.69 0)
		(unit 1)
		(exclude_from_sim no)
		(in_bom yes)
		(on_board yes)
		(dnp no)
		(property "Reference" "#PWR026"
			(at 233.68 186.69 0)
			(effects
				(font
					(size 1.27 1.27)
					(thickness 0.15)
				)
				(justify left bottom)
				(hide yes)
			)
		)
		(property "Value" "+3V3"
			(at 218.44 182.88 0)
			(effects
				(font
					(size 1.27 1.27)
					(thickness 0.15)
				)
			)
		)
		(property "Footprint" ""
			(at 233.68 194.31 0)
			(effects
				(font
					(size 1.27 1.27)
					(thickness 0.15)
				)
				(justify left bottom)
				(hide yes)
			)
		)
		(property "Datasheet" ""
			(at 233.68 196.85 0)
			(effects
				(font
					(size 1.27 1.27)
					(thickness 0.15)
				)
				(justify left bottom)
				(hide yes)
			)
		)
		(property "Description" ""
			(at 218.44 186.69 0)
			(effects
				(font
					(size 1.27 1.27)
				)
				(hide yes)
			)
		)
		(property "Author" "Antmicro"
			(at 233.68 189.23 0)
			(effects
				(font
					(size 1.27 1.27)
					(thickness 0.15)
				)
				(justify left bottom)
				(hide yes)
			)
		)
		(property "License" "Apache-2.0"
			(at 233.68 191.77 0)
			(effects
				(font
					(size 1.27 1.27)
					(thickness 0.15)
				)
				(justify left bottom)
				(hide yes)
			)
		)
		(pin "1"
		)
		(instances
			(project "cm4-baseboard"
				(path ""
					(reference "#PWR026")
					(unit 1)
				)
			)
		)
	)
	(symbol
		(lib_id "antmicroResistors0402:R_100k_0402")
		(at 189.23 222.25 90)
		(unit 1)
		(exclude_from_sim no)
		(in_bom yes)
		(on_board yes)
		(dnp no)
		(property "Reference" "R263"
			(at 190.5 218.44 90)
			(effects
				(font
					(size 1.27 1.27)
				)
				(justify right)
			)
		)
		(property "Value" "R_100k_0402"
			(at 193.04 222.25 0)
			(effects
				(font
					(size 1.27 1.27)
				)
				(justify left bottom)
				(hide yes)
			)
		)
		(property "Footprint" "antmicro-footprints:R_0402_1005Metric"
			(at 184.15 217.17 0)
			(effects
				(font
					(size 1.524 1.524)
				)
				(justify left bottom)
				(hide yes)
			)
		)
		(property "Datasheet" "https://www.bourns.com/docs/product-datasheets/cr.pdf"
			(at 189.23 222.25 0)
			(effects
				(font
					(size 1.27 1.27)
				)
				(justify left bottom)
				(hide yes)
			)
		)
		(property "Description" ""
			(at 189.23 222.25 0)
			(effects
				(font
					(size 1.27 1.27)
				)
				(hide yes)
			)
		)
		(property "Manufacturer" "Bourns"
			(at 179.07 217.17 0)
			(effects
				(font
					(size 1.524 1.524)
				)
				(justify left bottom)
				(hide yes)
			)
		)
		(property "MPN" "CR0402-FX-1003GLF"
			(at 181.61 217.17 0)
			(effects
				(font
					(size 1.524 1.524)
				)
				(justify left bottom)
				(hide yes)
			)
		)
		(property "Val" "100k"
			(at 190.5 220.98 90)
			(effects
				(font
					(size 1.27 1.27)
				)
				(justify right)
			)
		)
		(property "License" "Apache-2.0"
			(at 214.63 201.93 0)
			(effects
				(font
					(size 1.27 1.27)
					(thickness 0.15)
				)
				(justify left bottom)
				(hide yes)
			)
		)
		(property "Author" "Antmicro"
			(at 217.17 201.93 0)
			(effects
				(font
					(size 1.27 1.27)
					(thickness 0.15)
				)
				(justify left bottom)
				(hide yes)
			)
		)
		(property "Tolerance" "1%"
			(at 199.39 201.93 0)
			(effects
				(font
					(size 1.27 1.27)
				)
				(justify left bottom)
				(hide yes)
			)
		)
		(pin "1"
		)
		(pin "2"
		)
		(instances
			(project "cm4-baseboard"
				(path ""
					(reference "R263")
					(unit 1)
				)
			)
		)
	)
	(symbol
		(lib_id "antmicroResistors0402:R_2k2_0402")
		(at 191.77 276.86 270)
		(mirror x)
		(unit 1)
		(exclude_from_sim no)
		(in_bom yes)
		(on_board yes)
		(dnp no)
		(property "Reference" "R243"
			(at 193.04 273.05 90)
			(effects
				(font
					(size 1.27 1.27)
					(thickness 0.15)
				)
				(justify left)
			)
		)
		(property "Value" "R_2k2_0402"
			(at 179.07 256.54 0)
			(effects
				(font
					(size 1.27 1.27)
					(thickness 0.15)
				)
				(justify left bottom)
				(hide yes)
			)
		)
		(property "Footprint" "antmicro-footprints:R_0402_1005Metric"
			(at 176.53 256.54 0)
			(effects
				(font
					(size 1.27 1.27)
					(thickness 0.15)
				)
				(justify left bottom)
				(hide yes)
			)
		)
		(property "Datasheet" "https://www.bourns.com/docs/product-datasheets/cr.pdf"
			(at 173.99 256.54 0)
			(effects
				(font
					(size 1.27 1.27)
					(thickness 0.15)
				)
				(justify left bottom)
				(hide yes)
			)
		)
		(property "Description" ""
			(at 191.77 276.86 0)
			(effects
				(font
					(size 1.27 1.27)
				)
				(hide yes)
			)
		)
		(property "MPN" "CR0402-FX-2201GLF"
			(at 171.45 256.54 0)
			(effects
				(font
					(size 1.27 1.27)
					(thickness 0.15)
				)
				(justify left bottom)
				(hide yes)
			)
		)
		(property "Manufacturer" "Bourns"
			(at 168.91 256.54 0)
			(effects
				(font
					(size 1.27 1.27)
					(thickness 0.15)
				)
				(justify left bottom)
				(hide yes)
			)
		)
		(property "License" "Apache-2.0"
			(at 166.37 256.54 0)
			(effects
				(font
					(size 1.27 1.27)
					(thickness 0.15)
				)
				(justify left bottom)
				(hide yes)
			)
		)
		(property "Author" "Antmicro"
			(at 163.83 256.54 0)
			(effects
				(font
					(size 1.27 1.27)
					(thickness 0.15)
				)
				(justify left bottom)
				(hide yes)
			)
		)
		(property "Val" "2k2"
			(at 193.04 275.59 90)
			(effects
				(font
					(size 1.27 1.27)
					(thickness 0.15)
				)
				(justify left)
			)
		)
		(property "Tolerance" "1%"
			(at 181.61 256.54 0)
			(effects
				(font
					(size 1.27 1.27)
				)
				(justify left bottom)
				(hide yes)
			)
		)
		(pin "1"
		)
		(pin "2"
		)
		(instances
			(project "cm4-baseboard"
				(path ""
					(reference "R243")
					(unit 1)
				)
			)
		)
	)
	(symbol
		(lib_id "antmicroResistors0402:R_10k_0402")
		(at 240.03 62.23 270)
		(mirror x)
		(unit 1)
		(exclude_from_sim no)
		(in_bom no)
		(on_board yes)
		(dnp yes)
		(property "Reference" "R230"
			(at 238.76 58.42 90)
			(effects
				(font
					(size 1.27 1.27)
					(thickness 0.15)
				)
				(justify right)
			)
		)
		(property "Value" "R_10k_0402"
			(at 227.33 41.91 0)
			(effects
				(font
					(size 1.27 1.27)
					(thickness 0.15)
				)
				(justify left bottom)
				(hide yes)
			)
		)
		(property "Footprint" "antmicro-footprints:R_0402_1005Metric"
			(at 224.79 41.91 0)
			(effects
				(font
					(size 1.27 1.27)
					(thickness 0.15)
				)
				(justify left bottom)
				(hide yes)
			)
		)
		(property "Datasheet" "https://www.bourns.com/docs/product-datasheets/cr.pdf"
			(at 222.25 41.91 0)
			(effects
				(font
					(size 1.27 1.27)
					(thickness 0.15)
				)
				(justify left bottom)
				(hide yes)
			)
		)
		(property "Description" ""
			(at 240.03 62.23 0)
			(effects
				(font
					(size 1.27 1.27)
				)
				(hide yes)
			)
		)
		(property "MPN" "CR0402-FX-1002GLF"
			(at 219.71 41.91 0)
			(effects
				(font
					(size 1.27 1.27)
					(thickness 0.15)
				)
				(justify left bottom)
				(hide yes)
			)
		)
		(property "Manufacturer" "Bourns"
			(at 217.17 41.91 0)
			(effects
				(font
					(size 1.27 1.27)
					(thickness 0.15)
				)
				(justify left bottom)
				(hide yes)
			)
		)
		(property "License" "Apache-2.0"
			(at 214.63 41.91 0)
			(effects
				(font
					(size 1.27 1.27)
					(thickness 0.15)
				)
				(justify left bottom)
				(hide yes)
			)
		)
		(property "Author" "Antmicro"
			(at 212.09 41.91 0)
			(effects
				(font
					(size 1.27 1.27)
					(thickness 0.15)
				)
				(justify left bottom)
				(hide yes)
			)
		)
		(property "Val" "10k"
			(at 238.76 60.96 90)
			(effects
				(font
					(size 1.27 1.27)
					(thickness 0.15)
				)
				(justify right)
			)
		)
		(property "Tolerance" "1%"
			(at 229.87 41.91 0)
			(effects
				(font
					(size 1.27 1.27)
				)
				(justify left bottom)
				(hide yes)
			)
		)
		(pin "1"
		)
		(pin "2"
		)
		(instances
			(project "cm4-baseboard"
				(path ""
					(reference "R230")
					(unit 1)
				)
			)
		)
	)
	(symbol
		(lib_id "antmicropower:+5V")
		(at 80.01 129.54 0)
		(unit 1)
		(exclude_from_sim no)
		(in_bom yes)
		(on_board yes)
		(dnp no)
		(property "Reference" "#PWR0208"
			(at 95.25 132.08 0)
			(effects
				(font
					(size 1.27 1.27)
					(thickness 0.15)
				)
				(justify left bottom)
				(hide yes)
			)
		)
		(property "Value" "+5V"
			(at 82.55 128.905 0)
			(effects
				(font
					(size 1.27 1.27)
					(thickness 0.15)
				)
			)
		)
		(property "Footprint" ""
			(at 95.25 137.16 0)
			(effects
				(font
					(size 1.27 1.27)
					(thickness 0.15)
				)
				(justify left bottom)
				(hide yes)
			)
		)
		(property "Datasheet" ""
			(at 95.25 139.7 0)
			(effects
				(font
					(size 1.27 1.27)
					(thickness 0.15)
				)
				(justify left bottom)
				(hide yes)
			)
		)
		(property "Description" ""
			(at 80.01 129.54 0)
			(effects
				(font
					(size 1.27 1.27)
				)
				(hide yes)
			)
		)
		(property "Author" "Antmicro"
			(at 95.25 137.16 0)
			(effects
				(font
					(size 1.27 1.27)
					(thickness 0.15)
				)
				(justify left bottom)
				(hide yes)
			)
		)
		(property "License" "Apache-2.0"
			(at 95.25 139.7 0)
			(effects
				(font
					(size 1.27 1.27)
					(thickness 0.15)
				)
				(justify left bottom)
				(hide yes)
			)
		)
		(pin "1"
		)
		(instances
			(project "cm4-baseboard"
				(path ""
					(reference "#PWR0208")
					(unit 1)
				)
			)
		)
	)
	(symbol
		(lib_id "antmicroTestPoints:TP_0.75mm_SMD")
		(at 44.45 54.61 180)
		(unit 1)
		(exclude_from_sim no)
		(in_bom no)
		(on_board yes)
		(dnp no)
		(property "Reference" "TP204"
			(at 34.29 54.61 0)
			(effects
				(font
					(size 1.27 1.27)
					(thickness 0.15)
				)
				(justify right)
			)
		)
		(property "Value" "TP_0.75mm_SMD"
			(at 29.21 46.99 0)
			(effects
				(font
					(size 1.27 1.27)
					(thickness 0.15)
				)
				(justify left bottom)
				(hide yes)
			)
		)
		(property "Footprint" "antmicro-footprints:TP_SMD_0.75mm"
			(at 33.655 48.26 0)
			(effects
				(font
					(size 1.27 1.27)
					(thickness 0.15)
				)
				(justify left bottom)
				(hide yes)
			)
		)
		(property "Datasheet" ""
			(at 26.67 41.91 0)
			(effects
				(font
					(size 1.27 1.27)
					(thickness 0.15)
				)
				(justify left bottom)
				(hide yes)
			)
		)
		(property "Description" ""
			(at 44.45 54.61 0)
			(effects
				(font
					(size 1.27 1.27)
				)
				(hide yes)
			)
		)
		(property "Author" "Antmicro"
			(at 33.655 45.72 0)
			(effects
				(font
					(size 1.27 1.27)
					(thickness 0.15)
				)
				(justify left bottom)
				(hide yes)
			)
		)
		(property "License" "Apache-2.0"
			(at 33.655 43.18 0)
			(effects
				(font
					(size 1.27 1.27)
					(thickness 0.15)
				)
				(justify left bottom)
				(hide yes)
			)
		)
		(property "MPN" ""
			(at 33.655 43.18 0)
			(effects
				(font
					(size 1.27 1.27)
					(thickness 0.15)
				)
				(justify left bottom)
				(hide yes)
			)
		)
		(property "Manufacturer" ""
			(at 33.655 48.26 0)
			(effects
				(font
					(size 1.27 1.27)
					(thickness 0.15)
				)
				(justify left bottom)
				(hide yes)
			)
		)
		(pin "1"
		)
		(instances
			(project "cm4-baseboard"
				(path ""
					(reference "TP204")
					(unit 1)
				)
			)
		)
	)
	(symbol
		(lib_id "antmicroInterfaceIOExpanders:MCP23017T-E_QFN")
		(at 278.13 35.56 0)
		(unit 1)
		(exclude_from_sim no)
		(in_bom yes)
		(on_board yes)
		(dnp no)
		(fields_autoplaced yes)
		(property "Reference" "U204"
			(at 290.83 27.94 0)
			(effects
				(font
					(size 1.27 1.27)
					(thickness 0.15)
				)
			)
		)
		(property "Value" "MCP23017T-E_QFN"
			(at 316.23 46.99 0)
			(effects
				(font
					(size 1.27 1.27)
					(thickness 0.15)
				)
				(justify left bottom)
				(hide yes)
			)
		)
		(property "Footprint" "antmicro-footprints:QFN-28-1EP_6x6mm_P0.65mm_EP3.7x3.7mm"
			(at 316.23 49.53 0)
			(effects
				(font
					(size 1.27 1.27)
					(thickness 0.15)
				)
				(justify left bottom)
				(hide yes)
			)
		)
		(property "Datasheet" "https://ww1.microchip.com/downloads/aemDocuments/documents/APID/ProductDocuments/DataSheets/MCP23017-Data-Sheet-DS20001952.pdf"
			(at 316.23 52.07 0)
			(effects
				(font
					(size 1.27 1.27)
					(thickness 0.15)
				)
				(justify left bottom)
				(hide yes)
			)
		)
		(property "Description" ""
			(at 278.13 35.56 0)
			(effects
				(font
					(size 1.27 1.27)
				)
				(hide yes)
			)
		)
		(property "Manufacturer" "Microchip Technology"
			(at 316.23 54.61 0)
			(effects
				(font
					(size 1.27 1.27)
					(thickness 0.15)
				)
				(justify left bottom)
				(hide yes)
			)
		)
		(property "MPN" "MCP23017T-E/ML"
			(at 290.83 30.48 0)
			(effects
				(font
					(size 1.27 1.27)
					(thickness 0.15)
				)
			)
		)
		(property "Author" "Antmicro"
			(at 316.23 57.15 0)
			(effects
				(font
					(size 1.27 1.27)
					(thickness 0.15)
				)
				(justify left bottom)
				(hide yes)
			)
		)
		(property "License" "Apache-2.0"
			(at 316.23 59.69 0)
			(effects
				(font
					(size 1.27 1.27)
					(thickness 0.15)
				)
				(justify left bottom)
				(hide yes)
			)
		)
		(pin "1"
		)
		(pin "10"
		)
		(pin "11"
		)
		(pin "12"
		)
		(pin "13"
		)
		(pin "14"
		)
		(pin "15"
		)
		(pin "16"
		)
		(pin "17"
		)
		(pin "18"
		)
		(pin "19"
		)
		(pin "2"
		)
		(pin "20"
		)
		(pin "21"
		)
		(pin "22"
		)
		(pin "23"
		)
		(pin "24"
		)
		(pin "25"
		)
		(pin "26"
		)
		(pin "27"
		)
		(pin "28"
		)
		(pin "29"
		)
		(pin "3"
		)
		(pin "4"
		)
		(pin "5"
		)
		(pin "6"
		)
		(pin "7"
		)
		(pin "8"
		)
		(pin "9"
		)
		(instances
			(project "cm4-baseboard"
				(path ""
					(reference "U204")
					(unit 1)
				)
			)
		)
	)
	(symbol
		(lib_id "antmicropower:+3V3")
		(at 271.78 210.82 0)
		(unit 1)
		(exclude_from_sim no)
		(in_bom yes)
		(on_board yes)
		(dnp no)
		(property "Reference" "#PWR0249"
			(at 287.02 213.36 0)
			(effects
				(font
					(size 1.27 1.27)
					(thickness 0.15)
				)
				(justify left bottom)
				(hide yes)
			)
		)
		(property "Value" "+3V3"
			(at 271.145 207.01 0)
			(effects
				(font
					(size 1.27 1.27)
					(thickness 0.15)
				)
			)
		)
		(property "Footprint" ""
			(at 287.02 218.44 0)
			(effects
				(font
					(size 1.27 1.27)
					(thickness 0.15)
				)
				(justify left bottom)
				(hide yes)
			)
		)
		(property "Datasheet" ""
			(at 287.02 220.98 0)
			(effects
				(font
					(size 1.27 1.27)
					(thickness 0.15)
				)
				(justify left bottom)
				(hide yes)
			)
		)
		(property "Description" ""
			(at 271.78 210.82 0)
			(effects
				(font
					(size 1.27 1.27)
				)
				(hide yes)
			)
		)
		(property "Author" "Antmicro"
			(at 287.02 218.44 0)
			(effects
				(font
					(size 1.27 1.27)
					(thickness 0.15)
				)
				(justify left bottom)
				(hide yes)
			)
		)
		(property "License" "Apache-2.0"
			(at 287.02 220.98 0)
			(effects
				(font
					(size 1.27 1.27)
					(thickness 0.15)
				)
				(justify left bottom)
				(hide yes)
			)
		)
		(pin "1"
		)
		(instances
			(project "cm4-baseboard"
				(path ""
					(reference "#PWR0249")
					(unit 1)
				)
			)
		)
	)
	(symbol
		(lib_id "antmicroResistors0402:R_100k_0402")
		(at 31.75 241.3 0)
		(unit 1)
		(exclude_from_sim no)
		(in_bom yes)
		(on_board yes)
		(dnp no)
		(property "Reference" "R203"
			(at 34.29 236.22 0)
			(effects
				(font
					(size 1.27 1.27)
					(thickness 0.15)
				)
			)
		)
		(property "Value" "R_100k_0402"
			(at 52.07 254 0)
			(effects
				(font
					(size 1.27 1.27)
					(thickness 0.15)
				)
				(justify left bottom)
				(hide yes)
			)
		)
		(property "Footprint" "antmicro-footprints:R_0402_1005Metric"
			(at 52.07 256.54 0)
			(effects
				(font
					(size 1.27 1.27)
					(thickness 0.15)
				)
				(justify left bottom)
				(hide yes)
			)
		)
		(property "Datasheet" "https://www.bourns.com/docs/product-datasheets/cr.pdf"
			(at 52.07 259.08 0)
			(effects
				(font
					(size 1.27 1.27)
					(thickness 0.15)
				)
				(justify left bottom)
				(hide yes)
			)
		)
		(property "Description" ""
			(at 31.75 241.3 0)
			(effects
				(font
					(size 1.27 1.27)
				)
				(hide yes)
			)
		)
		(property "MPN" "CR0402-FX-1003GLF"
			(at 52.07 261.62 0)
			(effects
				(font
					(size 1.27 1.27)
					(thickness 0.15)
				)
				(justify left bottom)
				(hide yes)
			)
		)
		(property "Manufacturer" "Bourns"
			(at 52.07 264.16 0)
			(effects
				(font
					(size 1.27 1.27)
					(thickness 0.15)
				)
				(justify left bottom)
				(hide yes)
			)
		)
		(property "License" "Apache-2.0"
			(at 52.07 266.7 0)
			(effects
				(font
					(size 1.27 1.27)
					(thickness 0.15)
				)
				(justify left bottom)
				(hide yes)
			)
		)
		(property "Author" "Antmicro"
			(at 52.07 269.24 0)
			(effects
				(font
					(size 1.27 1.27)
					(thickness 0.15)
				)
				(justify left bottom)
				(hide yes)
			)
		)
		(property "Val" "100k"
			(at 34.29 238.76 0)
			(effects
				(font
					(size 1.27 1.27)
					(thickness 0.15)
				)
			)
		)
		(property "Tolerance" "1%"
			(at 52.07 251.46 0)
			(effects
				(font
					(size 1.27 1.27)
				)
				(justify left bottom)
				(hide yes)
			)
		)
		(pin "1"
		)
		(pin "2"
		)
		(instances
			(project "cm4-baseboard"
				(path ""
					(reference "R203")
					(unit 1)
				)
			)
		)
	)
	(symbol
		(lib_id "antmicropower:+3V3")
		(at 287.02 87.63 0)
		(unit 1)
		(exclude_from_sim no)
		(in_bom yes)
		(on_board yes)
		(dnp no)
		(fields_autoplaced yes)
		(property "Reference" "#PWR0258"
			(at 302.26 87.63 0)
			(effects
				(font
					(size 1.27 1.27)
					(thickness 0.15)
				)
				(justify left bottom)
				(hide yes)
			)
		)
		(property "Value" "+3V3"
			(at 287.02 82.55 0)
			(effects
				(font
					(size 1.27 1.27)
					(thickness 0.15)
				)
			)
		)
		(property "Footprint" ""
			(at 302.26 95.25 0)
			(effects
				(font
					(size 1.27 1.27)
					(thickness 0.15)
				)
				(justify left bottom)
				(hide yes)
			)
		)
		(property "Datasheet" ""
			(at 302.26 97.79 0)
			(effects
				(font
					(size 1.27 1.27)
					(thickness 0.15)
				)
				(justify left bottom)
				(hide yes)
			)
		)
		(property "Description" ""
			(at 287.02 87.63 0)
			(effects
				(font
					(size 1.27 1.27)
				)
				(hide yes)
			)
		)
		(property "Author" "Antmicro"
			(at 302.26 90.17 0)
			(effects
				(font
					(size 1.27 1.27)
					(thickness 0.15)
				)
				(justify left bottom)
				(hide yes)
			)
		)
		(property "License" "Apache-2.0"
			(at 302.26 92.71 0)
			(effects
				(font
					(size 1.27 1.27)
					(thickness 0.15)
				)
				(justify left bottom)
				(hide yes)
			)
		)
		(pin "1"
		)
		(instances
			(project "cm4-baseboard"
				(path ""
					(reference "#PWR0258")
					(unit 1)
				)
			)
		)
	)
	(symbol
		(lib_id "antmicroTestPoints:TP_0.75mm_SMD")
		(at 68.58 222.25 270)
		(unit 1)
		(exclude_from_sim no)
		(in_bom no)
		(on_board yes)
		(dnp no)
		(property "Reference" "TP216"
			(at 71.12 227.965 90)
			(effects
				(font
					(size 1.27 1.27)
				)
				(justify right)
			)
		)
		(property "Value" "TP_0.75mm_SMD"
			(at 66.04 222.25 0)
			(effects
				(font
					(size 1.27 1.27)
					(thickness 0.15)
				)
				(justify left bottom)
				(hide yes)
			)
		)
		(property "Footprint" "antmicro-footprints:TP_SMD_0.75mm"
			(at 73.66 227.33 0)
			(effects
				(font
					(size 1.27 1.27)
					(thickness 0.15)
				)
				(justify left bottom)
				(hide yes)
			)
		)
		(property "Datasheet" ""
			(at 76.2 227.33 0)
			(effects
				(font
					(size 1.27 1.27)
					(thickness 0.15)
				)
				(justify left bottom)
				(hide yes)
			)
		)
		(property "Description" ""
			(at 68.58 222.25 0)
			(effects
				(font
					(size 1.27 1.27)
				)
				(hide yes)
			)
		)
		(property "MPN" ""
			(at 68.58 222.25 0)
			(effects
				(font
					(size 1.27 1.27)
					(thickness 0.15)
				)
				(justify left bottom)
				(hide yes)
			)
		)
		(property "Manufacturer" ""
			(at 68.58 222.25 0)
			(effects
				(font
					(size 1.27 1.27)
					(thickness 0.15)
				)
				(justify left bottom)
				(hide yes)
			)
		)
		(property "Author" "Antmicro"
			(at 53.34 237.49 0)
			(effects
				(font
					(size 1.27 1.27)
					(thickness 0.15)
				)
				(justify left bottom)
				(hide yes)
			)
		)
		(property "License" "Apache-2.0"
			(at 50.8 237.49 0)
			(effects
				(font
					(size 1.27 1.27)
					(thickness 0.15)
				)
				(justify left bottom)
				(hide yes)
			)
		)
		(pin "1"
		)
		(instances
			(project "cm4-baseboard"
				(path ""
					(reference "TP216")
					(unit 1)
				)
			)
		)
	)
	(symbol
		(lib_id "antmicroResistors0402:R_470R_0402")
		(at 121.92 269.24 0)
		(unit 1)
		(exclude_from_sim no)
		(in_bom yes)
		(on_board yes)
		(dnp no)
		(property "Reference" "R211"
			(at 121.92 267.97 0)
			(effects
				(font
					(size 1.27 1.27)
					(thickness 0.15)
				)
				(justify left bottom)
			)
		)
		(property "Value" "R_470R_0402"
			(at 142.24 281.94 0)
			(effects
				(font
					(size 1.27 1.27)
					(thickness 0.15)
				)
				(justify left bottom)
				(hide yes)
			)
		)
		(property "Footprint" "antmicro-footprints:R_0402_1005Metric"
			(at 142.24 284.48 0)
			(effects
				(font
					(size 1.27 1.27)
					(thickness 0.15)
				)
				(justify left bottom)
				(hide yes)
			)
		)
		(property "Datasheet" "https://www.bourns.com/docs/product-datasheets/cr.pdf"
			(at 142.24 287.02 0)
			(effects
				(font
					(size 1.27 1.27)
					(thickness 0.15)
				)
				(justify left bottom)
				(hide yes)
			)
		)
		(property "Description" ""
			(at 121.92 269.24 0)
			(effects
				(font
					(size 1.27 1.27)
				)
				(hide yes)
			)
		)
		(property "Manufacturer" "Bourns"
			(at 142.24 292.1 0)
			(effects
				(font
					(size 1.27 1.27)
					(thickness 0.15)
				)
				(justify left bottom)
				(hide yes)
			)
		)
		(property "MPN" "CR0402-FX-4700GLF"
			(at 142.24 289.56 0)
			(effects
				(font
					(size 1.27 1.27)
					(thickness 0.15)
				)
				(justify left bottom)
				(hide yes)
			)
		)
		(property "Val" "470R"
			(at 121.92 273.05 0)
			(effects
				(font
					(size 1.27 1.27)
					(thickness 0.15)
				)
				(justify left bottom)
			)
		)
		(property "License" "Apache-2.0"
			(at 142.24 294.64 0)
			(effects
				(font
					(size 1.27 1.27)
					(thickness 0.15)
				)
				(justify left bottom)
				(hide yes)
			)
		)
		(property "Author" "Antmicro"
			(at 142.24 297.18 0)
			(effects
				(font
					(size 1.27 1.27)
					(thickness 0.15)
				)
				(justify left bottom)
				(hide yes)
			)
		)
		(property "Tolerance" "1%"
			(at 142.24 279.4 0)
			(effects
				(font
					(size 1.27 1.27)
				)
				(justify left bottom)
				(hide yes)
			)
		)
		(pin "1"
		)
		(pin "2"
		)
		(instances
			(project "cm4-baseboard"
				(path ""
					(reference "R211")
					(unit 1)
				)
			)
		)
	)
	(symbol
		(lib_id "antmicroResistors0402:R_0R_0402")
		(at 207.01 241.3 0)
		(unit 1)
		(exclude_from_sim no)
		(in_bom yes)
		(on_board yes)
		(dnp no)
		(fields_autoplaced yes)
		(property "Reference" "R258"
			(at 209.55 234.95 0)
			(effects
				(font
					(size 1.27 1.27)
				)
			)
		)
		(property "Value" "R_0R_0402"
			(at 207.01 245.11 0)
			(effects
				(font
					(size 1.27 1.27)
				)
				(justify left bottom)
				(hide yes)
			)
		)
		(property "Footprint" "antmicro-footprints:R_0402_1005Metric"
			(at 212.09 236.22 0)
			(effects
				(font
					(size 1.524 1.524)
				)
				(justify left bottom)
				(hide yes)
			)
		)
		(property "Datasheet" "https://industrial.panasonic.com/cdbs/www-data/pdf/RDA0000/AOA0000C301.pdf"
			(at 207.01 241.3 0)
			(effects
				(font
					(size 1.27 1.27)
				)
				(justify left bottom)
				(hide yes)
			)
		)
		(property "Description" ""
			(at 207.01 241.3 0)
			(effects
				(font
					(size 1.27 1.27)
				)
				(hide yes)
			)
		)
		(property "Manufacturer" "Panasonic"
			(at 212.09 231.14 0)
			(effects
				(font
					(size 1.524 1.524)
				)
				(justify left bottom)
				(hide yes)
			)
		)
		(property "MPN" "ERJ2GE0R00X"
			(at 212.09 233.68 0)
			(effects
				(font
					(size 1.524 1.524)
				)
				(justify left bottom)
				(hide yes)
			)
		)
		(property "Val" "0R"
			(at 209.55 237.49 0)
			(effects
				(font
					(size 1.27 1.27)
				)
			)
		)
		(property "License" "Apache-2.0"
			(at 227.33 266.7 0)
			(effects
				(font
					(size 1.27 1.27)
					(thickness 0.15)
				)
				(justify left bottom)
				(hide yes)
			)
		)
		(property "Author" "Antmicro"
			(at 227.33 269.24 0)
			(effects
				(font
					(size 1.27 1.27)
					(thickness 0.15)
				)
				(justify left bottom)
				(hide yes)
			)
		)
		(property "Tolerance" "~"
			(at 227.33 251.46 0)
			(effects
				(font
					(size 1.27 1.27)
				)
				(justify left bottom)
				(hide yes)
			)
		)
		(property "Current" "1A"
			(at 209.55 239.395 0)
			(effects
				(font
					(size 1.27 1.27)
					(thickness 0.15)
				)
				(hide yes)
			)
		)
		(pin "1"
		)
		(pin "2"
		)
		(instances
			(project "cm4-baseboard"
				(path ""
					(reference "R258")
					(unit 1)
				)
			)
		)
	)
	(symbol
		(lib_id "antmicroPushbuttonSwitches:SW_KMR211NGLFS_SMD")
		(at 132.08 187.96 90)
		(mirror x)
		(unit 1)
		(exclude_from_sim no)
		(in_bom yes)
		(on_board yes)
		(dnp no)
		(property "Reference" "S201"
			(at 128.27 191.77 90)
			(effects
				(font
					(size 1.27 1.27)
				)
				(justify left)
			)
		)
		(property "Value" "SW_KMR211NGLFS_SMD"
			(at 144.78 194.31 90)
			(effects
				(font
					(size 1.27 1.27)
				)
				(justify left)
				(hide yes)
			)
		)
		(property "Footprint" "antmicro-footprints:SW_KMR211NGLFS_SMD"
			(at 127 193.04 0)
			(effects
				(font
					(size 1.27 1.27)
				)
				(justify left bottom)
				(hide yes)
			)
		)
		(property "Datasheet" "http://www.farnell.com/datasheets/2631211.pdf"
			(at 124.46 193.04 0)
			(effects
				(font
					(size 1.524 1.524)
				)
				(justify left bottom)
				(hide yes)
			)
		)
		(property "Description" ""
			(at 132.08 187.96 0)
			(effects
				(font
					(size 1.27 1.27)
				)
				(hide yes)
			)
		)
		(property "MPN" "KMR211NGLFS"
			(at 128.27 195.58 90)
			(effects
				(font
					(size 1.27 1.27)
				)
				(justify left bottom)
			)
		)
		(property "Manufacturer" "C&K"
			(at 120.0912 193.04 0)
			(effects
				(font
					(size 1.524 1.524)
				)
				(justify left bottom)
				(hide yes)
			)
		)
		(property "Author" "Antmicro"
			(at 149.86 213.36 0)
			(effects
				(font
					(size 1.27 1.27)
					(thickness 0.15)
				)
				(justify left bottom)
				(hide yes)
			)
		)
		(property "License" "Apache-2.0"
			(at 152.4 213.36 0)
			(effects
				(font
					(size 1.27 1.27)
					(thickness 0.15)
				)
				(justify left bottom)
				(hide yes)
			)
		)
		(pin "1"
		)
		(pin "2"
		)
		(pin "3"
		)
		(pin "4"
		)
		(instances
			(project "cm4-baseboard"
				(path ""
					(reference "S201")
					(unit 1)
				)
			)
		)
	)
	(symbol
		(lib_id "antmicroTransistorsFETsMOSFETsSingle:PJE138K")
		(at 142.24 201.93 0)
		(unit 1)
		(exclude_from_sim no)
		(in_bom yes)
		(on_board yes)
		(dnp no)
		(fields_autoplaced yes)
		(property "Reference" "Q208"
			(at 153.67 198.1199 0)
			(effects
				(font
					(size 1.27 1.27)
				)
				(justify left)
			)
		)
		(property "Value" "PJE138K"
			(at 153.67 200.6599 0)
			(effects
				(font
					(size 1.27 1.27)
				)
				(justify left)
			)
		)
		(property "Footprint" "antmicro-footprints:SOT-523"
			(at 147.32 196.85 0)
			(effects
				(font
					(size 1.524 1.524)
				)
				(justify left bottom)
				(hide yes)
			)
		)
		(property "Datasheet" "https://www.mouser.com/datasheet/2/1057/PJE138K-1876698.pdf"
			(at 147.32 194.31 0)
			(effects
				(font
					(size 1.524 1.524)
				)
				(justify left bottom)
				(hide yes)
			)
		)
		(property "Description" ""
			(at 142.24 201.93 0)
			(effects
				(font
					(size 1.27 1.27)
				)
				(hide yes)
			)
		)
		(property "MPN" "PJE138K_R1_00001"
			(at 158.75 191.77 0)
			(effects
				(font
					(size 1.524 1.524)
				)
				(justify left bottom)
				(hide yes)
			)
		)
		(property "Manufacturer" "PANJIT"
			(at 147.32 191.77 0)
			(effects
				(font
					(size 1.524 1.524)
				)
				(justify left bottom)
				(hide yes)
			)
		)
		(property "Author" "Antmicro"
			(at 165.1 223.52 0)
			(effects
				(font
					(size 1.27 1.27)
					(thickness 0.15)
				)
				(justify left bottom)
				(hide yes)
			)
		)
		(property "License" "Apache-2.0"
			(at 165.1 226.06 0)
			(effects
				(font
					(size 1.27 1.27)
					(thickness 0.15)
				)
				(justify left bottom)
				(hide yes)
			)
		)
		(pin "1"
		)
		(pin "2"
		)
		(pin "3"
		)
		(instances
			(project "cm4-baseboard"
				(path ""
					(reference "Q208")
					(unit 1)
				)
			)
		)
	)
	(symbol
		(lib_id "antmicroResistors0402:R_100k_0402")
		(at 349.25 243.84 90)
		(unit 1)
		(exclude_from_sim no)
		(in_bom yes)
		(on_board yes)
		(dnp no)
		(fields_autoplaced yes)
		(property "Reference" "R260"
			(at 346.71 240.03 90)
			(effects
				(font
					(size 1.27 1.27)
					(thickness 0.15)
				)
				(justify left)
			)
		)
		(property "Value" "R_100k_0402"
			(at 361.95 223.52 0)
			(effects
				(font
					(size 1.27 1.27)
					(thickness 0.15)
				)
				(justify left bottom)
				(hide yes)
			)
		)
		(property "Footprint" "antmicro-footprints:R_0402_1005Metric"
			(at 364.49 223.52 0)
			(effects
				(font
					(size 1.27 1.27)
					(thickness 0.15)
				)
				(justify left bottom)
				(hide yes)
			)
		)
		(property "Datasheet" "https://www.bourns.com/docs/product-datasheets/cr.pdf"
			(at 367.03 223.52 0)
			(effects
				(font
					(size 1.27 1.27)
					(thickness 0.15)
				)
				(justify left bottom)
				(hide yes)
			)
		)
		(property "Description" ""
			(at 349.25 243.84 0)
			(effects
				(font
					(size 1.27 1.27)
				)
				(hide yes)
			)
		)
		(property "MPN" "CR0402-FX-1003GLF"
			(at 369.57 223.52 0)
			(effects
				(font
					(size 1.27 1.27)
					(thickness 0.15)
				)
				(justify left bottom)
				(hide yes)
			)
		)
		(property "Manufacturer" "Bourns"
			(at 372.11 223.52 0)
			(effects
				(font
					(size 1.27 1.27)
					(thickness 0.15)
				)
				(justify left bottom)
				(hide yes)
			)
		)
		(property "License" "Apache-2.0"
			(at 374.65 223.52 0)
			(effects
				(font
					(size 1.27 1.27)
					(thickness 0.15)
				)
				(justify left bottom)
				(hide yes)
			)
		)
		(property "Author" "Antmicro"
			(at 377.19 223.52 0)
			(effects
				(font
					(size 1.27 1.27)
					(thickness 0.15)
				)
				(justify left bottom)
				(hide yes)
			)
		)
		(property "Val" "100k"
			(at 346.71 242.57 90)
			(effects
				(font
					(size 1.27 1.27)
					(thickness 0.15)
				)
				(justify left)
			)
		)
		(property "Tolerance" "1%"
			(at 359.41 223.52 0)
			(effects
				(font
					(size 1.27 1.27)
				)
				(justify left bottom)
				(hide yes)
			)
		)
		(pin "1"
		)
		(pin "2"
		)
		(instances
			(project "cm4-baseboard"
				(path ""
					(reference "R260")
					(unit 1)
				)
			)
		)
	)
	(symbol
		(lib_id "antmicropower:+3V3")
		(at 134.62 222.25 0)
		(unit 1)
		(exclude_from_sim no)
		(in_bom yes)
		(on_board yes)
		(dnp no)
		(property "Reference" "#PWR0218"
			(at 149.86 222.25 0)
			(effects
				(font
					(size 1.27 1.27)
					(thickness 0.15)
				)
				(justify left bottom)
				(hide yes)
			)
		)
		(property "Value" "+3V3"
			(at 134.62 218.44 0)
			(effects
				(font
					(size 1.27 1.27)
					(thickness 0.15)
				)
			)
		)
		(property "Footprint" ""
			(at 149.86 229.87 0)
			(effects
				(font
					(size 1.27 1.27)
					(thickness 0.15)
				)
				(justify left bottom)
				(hide yes)
			)
		)
		(property "Datasheet" ""
			(at 149.86 232.41 0)
			(effects
				(font
					(size 1.27 1.27)
					(thickness 0.15)
				)
				(justify left bottom)
				(hide yes)
			)
		)
		(property "Description" ""
			(at 134.62 222.25 0)
			(effects
				(font
					(size 1.27 1.27)
				)
				(hide yes)
			)
		)
		(property "Author" "Antmicro"
			(at 149.86 224.79 0)
			(effects
				(font
					(size 1.27 1.27)
					(thickness 0.15)
				)
				(justify left bottom)
				(hide yes)
			)
		)
		(property "License" "Apache-2.0"
			(at 149.86 227.33 0)
			(effects
				(font
					(size 1.27 1.27)
					(thickness 0.15)
				)
				(justify left bottom)
				(hide yes)
			)
		)
		(pin "1"
		)
		(instances
			(project "cm4-baseboard"
				(path ""
					(reference "#PWR0218")
					(unit 1)
				)
			)
		)
	)
	(symbol
		(lib_id "antmicroResistors0402:R_0R_0402")
		(at 156.21 105.41 0)
		(unit 1)
		(exclude_from_sim no)
		(in_bom yes)
		(on_board yes)
		(dnp no)
		(property "Reference" "R220"
			(at 153.67 104.14 0)
			(effects
				(font
					(size 1.27 1.27)
				)
			)
		)
		(property "Value" "R_0R_0402"
			(at 156.21 109.22 0)
			(effects
				(font
					(size 1.27 1.27)
				)
				(justify left bottom)
				(hide yes)
			)
		)
		(property "Footprint" "antmicro-footprints:R_0402_1005Metric"
			(at 161.29 100.33 0)
			(effects
				(font
					(size 1.524 1.524)
				)
				(justify left bottom)
				(hide yes)
			)
		)
		(property "Datasheet" "https://industrial.panasonic.com/cdbs/www-data/pdf/RDA0000/AOA0000C301.pdf"
			(at 156.21 105.41 0)
			(effects
				(font
					(size 1.27 1.27)
				)
				(justify left bottom)
				(hide yes)
			)
		)
		(property "Description" ""
			(at 156.21 105.41 0)
			(effects
				(font
					(size 1.27 1.27)
				)
				(hide yes)
			)
		)
		(property "Manufacturer" "Panasonic"
			(at 161.29 95.25 0)
			(effects
				(font
					(size 1.524 1.524)
				)
				(justify left bottom)
				(hide yes)
			)
		)
		(property "MPN" "ERJ2GE0R00X"
			(at 161.29 97.79 0)
			(effects
				(font
					(size 1.524 1.524)
				)
				(justify left bottom)
				(hide yes)
			)
		)
		(property "Val" "0R"
			(at 162.56 104.14 0)
			(effects
				(font
					(size 1.27 1.27)
				)
			)
		)
		(property "License" "Apache-2.0"
			(at 176.53 130.81 0)
			(effects
				(font
					(size 1.27 1.27)
					(thickness 0.15)
				)
				(justify left bottom)
				(hide yes)
			)
		)
		(property "Author" "Antmicro"
			(at 176.53 133.35 0)
			(effects
				(font
					(size 1.27 1.27)
					(thickness 0.15)
				)
				(justify left bottom)
				(hide yes)
			)
		)
		(property "Tolerance" "~"
			(at 176.53 115.57 0)
			(effects
				(font
					(size 1.27 1.27)
				)
				(justify left bottom)
				(hide yes)
			)
		)
		(property "Current" "1A"
			(at 158.75 103.505 0)
			(effects
				(font
					(size 1.27 1.27)
					(thickness 0.15)
				)
				(hide yes)
			)
		)
		(pin "1"
		)
		(pin "2"
		)
		(instances
			(project "cm4-baseboard"
				(path ""
					(reference "R220")
					(unit 1)
				)
			)
		)
	)
	(symbol
		(lib_id "antmicroResistors0402:R_100k_0402")
		(at 123.19 208.28 90)
		(unit 1)
		(exclude_from_sim no)
		(in_bom yes)
		(on_board yes)
		(dnp no)
		(property "Reference" "R212"
			(at 124.46 204.47 90)
			(effects
				(font
					(size 1.27 1.27)
				)
				(justify right)
			)
		)
		(property "Value" "R_100k_0402"
			(at 127 208.28 0)
			(effects
				(font
					(size 1.27 1.27)
				)
				(justify left bottom)
				(hide yes)
			)
		)
		(property "Footprint" "antmicro-footprints:R_0402_1005Metric"
			(at 118.11 203.2 0)
			(effects
				(font
					(size 1.524 1.524)
				)
				(justify left bottom)
				(hide yes)
			)
		)
		(property "Datasheet" "https://www.bourns.com/docs/product-datasheets/cr.pdf"
			(at 123.19 208.28 0)
			(effects
				(font
					(size 1.27 1.27)
				)
				(justify left bottom)
				(hide yes)
			)
		)
		(property "Description" ""
			(at 123.19 208.28 0)
			(effects
				(font
					(size 1.27 1.27)
				)
				(hide yes)
			)
		)
		(property "Manufacturer" "Bourns"
			(at 113.03 203.2 0)
			(effects
				(font
					(size 1.524 1.524)
				)
				(justify left bottom)
				(hide yes)
			)
		)
		(property "MPN" "CR0402-FX-1003GLF"
			(at 115.57 203.2 0)
			(effects
				(font
					(size 1.524 1.524)
				)
				(justify left bottom)
				(hide yes)
			)
		)
		(property "Val" "100k"
			(at 124.46 207.01 90)
			(effects
				(font
					(size 1.27 1.27)
				)
				(justify right)
			)
		)
		(property "License" "Apache-2.0"
			(at 148.59 187.96 0)
			(effects
				(font
					(size 1.27 1.27)
					(thickness 0.15)
				)
				(justify left bottom)
				(hide yes)
			)
		)
		(property "Author" "Antmicro"
			(at 151.13 187.96 0)
			(effects
				(font
					(size 1.27 1.27)
					(thickness 0.15)
				)
				(justify left bottom)
				(hide yes)
			)
		)
		(property "Tolerance" "1%"
			(at 133.35 187.96 0)
			(effects
				(font
					(size 1.27 1.27)
				)
				(justify left bottom)
				(hide yes)
			)
		)
		(pin "1"
		)
		(pin "2"
		)
		(instances
			(project "cm4-baseboard"
				(path ""
					(reference "R212")
					(unit 1)
				)
			)
		)
	)
	(symbol
		(lib_id "antmicroTVSDiodes:TPD1E0B04_XDFN-2")
		(at 114.3 208.28 90)
		(unit 1)
		(exclude_from_sim no)
		(in_bom yes)
		(on_board yes)
		(dnp no)
		(fields_autoplaced yes)
		(property "Reference" "D203"
			(at 111.76 204.4699 90)
			(effects
				(font
					(size 1.27 1.27)
				)
				(justify left)
			)
		)
		(property "Value" "TPD1E0B04_XDFN-2"
			(at 111.76 207.0099 90)
			(effects
				(font
					(size 1.27 1.27)
				)
				(justify left)
			)
		)
		(property "Footprint" "antmicro-footprints:XDFN-2_1x0.60mm"
			(at 109.22 203.2 0)
			(effects
				(font
					(size 1.524 1.524)
				)
				(justify left bottom)
				(hide yes)
			)
		)
		(property "Datasheet" "https://www.ti.com/general/docs/suppproductinfo.tsp?distId=26&gotoUrl=https://www.ti.com/lit/gpn/tpd1e0b04"
			(at 106.68 203.2 0)
			(effects
				(font
					(size 1.524 1.524)
				)
				(justify left bottom)
				(hide yes)
			)
		)
		(property "Description" ""
			(at 114.3 208.28 0)
			(effects
				(font
					(size 1.27 1.27)
				)
				(hide yes)
			)
		)
		(property "Manufacturer" "Texas Instruments"
			(at 86.36 203.2 0)
			(effects
				(font
					(size 1.524 1.524)
				)
				(justify left bottom)
				(hide yes)
			)
		)
		(property "MPN" "TPD1E0B04DPYR"
			(at 101.6 203.2 0)
			(effects
				(font
					(size 1.524 1.524)
				)
				(justify left bottom)
				(hide yes)
			)
		)
		(property "Author" "Antmicro"
			(at 129.54 193.04 0)
			(effects
				(font
					(size 1.27 1.27)
					(thickness 0.15)
				)
				(justify left bottom)
				(hide yes)
			)
		)
		(property "License" "Apache-2.0"
			(at 132.08 193.04 0)
			(effects
				(font
					(size 1.27 1.27)
					(thickness 0.15)
				)
				(justify left bottom)
				(hide yes)
			)
		)
		(pin "1"
		)
		(pin "2"
		)
		(instances
			(project "cm4-baseboard"
				(path ""
					(reference "D203")
					(unit 1)
				)
			)
		)
	)
	(symbol
		(lib_id "antmicroResistors0402:R_0R_0402")
		(at 196.85 113.03 0)
		(unit 1)
		(exclude_from_sim no)
		(in_bom yes)
		(on_board yes)
		(dnp no)
		(property "Reference" "R227"
			(at 194.31 111.76 0)
			(effects
				(font
					(size 1.27 1.27)
				)
			)
		)
		(property "Value" "R_0R_0402"
			(at 196.85 116.84 0)
			(effects
				(font
					(size 1.27 1.27)
				)
				(justify left bottom)
				(hide yes)
			)
		)
		(property "Footprint" "antmicro-footprints:R_0402_1005Metric"
			(at 201.93 107.95 0)
			(effects
				(font
					(size 1.524 1.524)
				)
				(justify left bottom)
				(hide yes)
			)
		)
		(property "Datasheet" "https://industrial.panasonic.com/cdbs/www-data/pdf/RDA0000/AOA0000C301.pdf"
			(at 196.85 113.03 0)
			(effects
				(font
					(size 1.27 1.27)
				)
				(justify left bottom)
				(hide yes)
			)
		)
		(property "Description" ""
			(at 196.85 113.03 0)
			(effects
				(font
					(size 1.27 1.27)
				)
				(hide yes)
			)
		)
		(property "Manufacturer" "Panasonic"
			(at 201.93 102.87 0)
			(effects
				(font
					(size 1.524 1.524)
				)
				(justify left bottom)
				(hide yes)
			)
		)
		(property "MPN" "ERJ2GE0R00X"
			(at 201.93 105.41 0)
			(effects
				(font
					(size 1.524 1.524)
				)
				(justify left bottom)
				(hide yes)
			)
		)
		(property "Val" "0R"
			(at 203.2 111.76 0)
			(effects
				(font
					(size 1.27 1.27)
				)
			)
		)
		(property "License" "Apache-2.0"
			(at 217.17 138.43 0)
			(effects
				(font
					(size 1.27 1.27)
					(thickness 0.15)
				)
				(justify left bottom)
				(hide yes)
			)
		)
		(property "Author" "Antmicro"
			(at 217.17 140.97 0)
			(effects
				(font
					(size 1.27 1.27)
					(thickness 0.15)
				)
				(justify left bottom)
				(hide yes)
			)
		)
		(property "Tolerance" "~"
			(at 217.17 123.19 0)
			(effects
				(font
					(size 1.27 1.27)
				)
				(justify left bottom)
				(hide yes)
			)
		)
		(property "Current" "1A"
			(at 199.39 111.125 0)
			(effects
				(font
					(size 1.27 1.27)
					(thickness 0.15)
				)
				(hide yes)
			)
		)
		(pin "1"
		)
		(pin "2"
		)
		(instances
			(project "cm4-baseboard"
				(path ""
					(reference "R227")
					(unit 1)
				)
			)
		)
	)
	(symbol
		(lib_id "antmicropower:GND")
		(at 148.59 209.55 0)
		(unit 1)
		(exclude_from_sim no)
		(in_bom yes)
		(on_board yes)
		(dnp no)
		(property "Reference" "#PWR0221"
			(at 148.59 215.9 0)
			(effects
				(font
					(size 1.27 1.27)
				)
				(justify left bottom)
				(hide yes)
			)
		)
		(property "Value" "GND"
			(at 148.59 213.36 0)
			(effects
				(font
					(size 1.27 1.27)
				)
			)
		)
		(property "Footprint" ""
			(at 157.48 217.17 0)
			(effects
				(font
					(size 1.27 1.27)
					(thickness 0.15)
				)
				(justify left bottom)
				(hide yes)
			)
		)
		(property "Datasheet" ""
			(at 157.48 222.25 0)
			(effects
				(font
					(size 1.27 1.27)
					(thickness 0.15)
				)
				(justify left bottom)
				(hide yes)
			)
		)
		(property "Description" ""
			(at 148.59 209.55 0)
			(effects
				(font
					(size 1.27 1.27)
				)
				(hide yes)
			)
		)
		(property "Author" "Antmicro"
			(at 157.48 217.17 0)
			(effects
				(font
					(size 1.27 1.27)
					(thickness 0.15)
				)
				(justify left bottom)
				(hide yes)
			)
		)
		(property "License" "Apache-2.0"
			(at 157.48 219.71 0)
			(effects
				(font
					(size 1.27 1.27)
					(thickness 0.15)
				)
				(justify left bottom)
				(hide yes)
			)
		)
		(pin "1"
		)
		(instances
			(project "cm4-baseboard"
				(path ""
					(reference "#PWR0221")
					(unit 1)
				)
			)
		)
	)
	(symbol
		(lib_id "antmicropower:GND")
		(at 40.64 64.77 0)
		(unit 1)
		(exclude_from_sim no)
		(in_bom yes)
		(on_board yes)
		(dnp no)
		(fields_autoplaced yes)
		(property "Reference" "#PWR0204"
			(at 49.53 67.31 0)
			(effects
				(font
					(size 1.27 1.27)
					(thickness 0.15)
				)
				(justify left bottom)
				(hide yes)
			)
		)
		(property "Value" "GND"
			(at 40.64 69.85 0)
			(effects
				(font
					(size 1.27 1.27)
					(thickness 0.15)
				)
			)
		)
		(property "Footprint" ""
			(at 49.53 72.39 0)
			(effects
				(font
					(size 1.27 1.27)
					(thickness 0.15)
				)
				(justify left bottom)
				(hide yes)
			)
		)
		(property "Datasheet" ""
			(at 49.53 77.47 0)
			(effects
				(font
					(size 1.27 1.27)
					(thickness 0.15)
				)
				(justify left bottom)
				(hide yes)
			)
		)
		(property "Description" ""
			(at 40.64 64.77 0)
			(effects
				(font
					(size 1.27 1.27)
				)
				(hide yes)
			)
		)
		(property "Author" "Antmicro"
			(at 49.53 72.39 0)
			(effects
				(font
					(size 1.27 1.27)
					(thickness 0.15)
				)
				(justify left bottom)
				(hide yes)
			)
		)
		(property "License" "Apache-2.0"
			(at 49.53 74.93 0)
			(effects
				(font
					(size 1.27 1.27)
					(thickness 0.15)
				)
				(justify left bottom)
				(hide yes)
			)
		)
		(pin "1"
		)
		(instances
			(project "cm4-baseboard"
				(path ""
					(reference "#PWR0204")
					(unit 1)
				)
			)
		)
	)
	(symbol
		(lib_id "antmicroResistors0402:R_100k_0402")
		(at 123.19 245.11 90)
		(unit 1)
		(exclude_from_sim no)
		(in_bom yes)
		(on_board yes)
		(dnp no)
		(property "Reference" "R213"
			(at 124.46 241.3 90)
			(effects
				(font
					(size 1.27 1.27)
				)
				(justify right)
			)
		)
		(property "Value" "R_100k_0402"
			(at 127 245.11 0)
			(effects
				(font
					(size 1.27 1.27)
				)
				(justify left bottom)
				(hide yes)
			)
		)
		(property "Footprint" "antmicro-footprints:R_0402_1005Metric"
			(at 118.11 240.03 0)
			(effects
				(font
					(size 1.524 1.524)
				)
				(justify left bottom)
				(hide yes)
			)
		)
		(property "Datasheet" "https://www.bourns.com/docs/product-datasheets/cr.pdf"
			(at 123.19 245.11 0)
			(effects
				(font
					(size 1.27 1.27)
				)
				(justify left bottom)
				(hide yes)
			)
		)
		(property "Description" ""
			(at 123.19 245.11 0)
			(effects
				(font
					(size 1.27 1.27)
				)
				(hide yes)
			)
		)
		(property "Manufacturer" "Bourns"
			(at 113.03 240.03 0)
			(effects
				(font
					(size 1.524 1.524)
				)
				(justify left bottom)
				(hide yes)
			)
		)
		(property "MPN" "CR0402-FX-1003GLF"
			(at 115.57 240.03 0)
			(effects
				(font
					(size 1.524 1.524)
				)
				(justify left bottom)
				(hide yes)
			)
		)
		(property "Val" "100k"
			(at 124.46 243.84 90)
			(effects
				(font
					(size 1.27 1.27)
				)
				(justify right)
			)
		)
		(property "License" "Apache-2.0"
			(at 148.59 224.79 0)
			(effects
				(font
					(size 1.27 1.27)
					(thickness 0.15)
				)
				(justify left bottom)
				(hide yes)
			)
		)
		(property "Author" "Antmicro"
			(at 151.13 224.79 0)
			(effects
				(font
					(size 1.27 1.27)
					(thickness 0.15)
				)
				(justify left bottom)
				(hide yes)
			)
		)
		(property "Tolerance" "1%"
			(at 133.35 224.79 0)
			(effects
				(font
					(size 1.27 1.27)
				)
				(justify left bottom)
				(hide yes)
			)
		)
		(pin "1"
		)
		(pin "2"
		)
		(instances
			(project "cm4-baseboard"
				(path ""
					(reference "R213")
					(unit 1)
				)
			)
		)
	)
	(symbol
		(lib_id "antmicropower:GND")
		(at 287.02 95.25 0)
		(unit 1)
		(exclude_from_sim no)
		(in_bom yes)
		(on_board yes)
		(dnp no)
		(fields_autoplaced yes)
		(property "Reference" "#PWR0259"
			(at 287.02 101.6 0)
			(effects
				(font
					(size 1.27 1.27)
				)
				(justify left bottom)
				(hide yes)
			)
		)
		(property "Value" "GND"
			(at 287.02 100.33 0)
			(effects
				(font
					(size 1.27 1.27)
				)
			)
		)
		(property "Footprint" ""
			(at 295.91 102.87 0)
			(effects
				(font
					(size 1.27 1.27)
					(thickness 0.15)
				)
				(justify left bottom)
				(hide yes)
			)
		)
		(property "Datasheet" ""
			(at 295.91 107.95 0)
			(effects
				(font
					(size 1.27 1.27)
					(thickness 0.15)
				)
				(justify left bottom)
				(hide yes)
			)
		)
		(property "Description" ""
			(at 287.02 95.25 0)
			(effects
				(font
					(size 1.27 1.27)
				)
				(hide yes)
			)
		)
		(property "Author" "Antmicro"
			(at 295.91 102.87 0)
			(effects
				(font
					(size 1.27 1.27)
					(thickness 0.15)
				)
				(justify left bottom)
				(hide yes)
			)
		)
		(property "License" "Apache-2.0"
			(at 295.91 105.41 0)
			(effects
				(font
					(size 1.27 1.27)
					(thickness 0.15)
				)
				(justify left bottom)
				(hide yes)
			)
		)
		(pin "1"
		)
		(instances
			(project "cm4-baseboard"
				(path ""
					(reference "#PWR0259")
					(unit 1)
				)
			)
		)
	)
	(symbol
		(lib_id "antmicropower:GND")
		(at 227.33 220.98 0)
		(unit 1)
		(exclude_from_sim no)
		(in_bom yes)
		(on_board yes)
		(dnp no)
		(fields_autoplaced yes)
		(property "Reference" "#PWR0211"
			(at 236.22 223.52 0)
			(effects
				(font
					(size 1.27 1.27)
					(thickness 0.15)
				)
				(justify left bottom)
				(hide yes)
			)
		)
		(property "Value" "GND"
			(at 225.3198 226.06 0)
			(effects
				(font
					(size 1.27 1.27)
					(thickness 0.15)
				)
				(justify left bottom)
			)
		)
		(property "Footprint" ""
			(at 236.22 228.6 0)
			(effects
				(font
					(size 1.27 1.27)
					(thickness 0.15)
				)
				(justify left bottom)
				(hide yes)
			)
		)
		(property "Datasheet" ""
			(at 236.22 233.68 0)
			(effects
				(font
					(size 1.27 1.27)
					(thickness 0.15)
				)
				(justify left bottom)
				(hide yes)
			)
		)
		(property "Description" ""
			(at 227.33 220.98 0)
			(effects
				(font
					(size 1.27 1.27)
				)
				(hide yes)
			)
		)
		(property "Author" "Antmicro"
			(at 236.22 228.6 0)
			(effects
				(font
					(size 1.27 1.27)
					(thickness 0.15)
				)
				(justify left bottom)
				(hide yes)
			)
		)
		(property "License" "Apache-2.0"
			(at 236.22 231.14 0)
			(effects
				(font
					(size 1.27 1.27)
					(thickness 0.15)
				)
				(justify left bottom)
				(hide yes)
			)
		)
		(pin "1"
		)
		(instances
			(project "cm4-baseboard"
				(path ""
					(reference "#PWR0211")
					(unit 1)
				)
			)
		)
	)
	(symbol
		(lib_id "antmicropower:GND")
		(at 293.37 95.25 0)
		(unit 1)
		(exclude_from_sim no)
		(in_bom yes)
		(on_board yes)
		(dnp no)
		(fields_autoplaced yes)
		(property "Reference" "#PWR0261"
			(at 293.37 101.6 0)
			(effects
				(font
					(size 1.27 1.27)
				)
				(justify left bottom)
				(hide yes)
			)
		)
		(property "Value" "GND"
			(at 293.37 100.33 0)
			(effects
				(font
					(size 1.27 1.27)
				)
			)
		)
		(property "Footprint" ""
			(at 302.26 102.87 0)
			(effects
				(font
					(size 1.27 1.27)
					(thickness 0.15)
				)
				(justify left bottom)
				(hide yes)
			)
		)
		(property "Datasheet" ""
			(at 302.26 107.95 0)
			(effects
				(font
					(size 1.27 1.27)
					(thickness 0.15)
				)
				(justify left bottom)
				(hide yes)
			)
		)
		(property "Description" ""
			(at 293.37 95.25 0)
			(effects
				(font
					(size 1.27 1.27)
				)
				(hide yes)
			)
		)
		(property "Author" "Antmicro"
			(at 302.26 102.87 0)
			(effects
				(font
					(size 1.27 1.27)
					(thickness 0.15)
				)
				(justify left bottom)
				(hide yes)
			)
		)
		(property "License" "Apache-2.0"
			(at 302.26 105.41 0)
			(effects
				(font
					(size 1.27 1.27)
					(thickness 0.15)
				)
				(justify left bottom)
				(hide yes)
			)
		)
		(pin "1"
		)
		(instances
			(project "cm4-baseboard"
				(path ""
					(reference "#PWR0261")
					(unit 1)
				)
			)
		)
	)
	(symbol
		(lib_id "antmicroResistors0402:R_0R_0402")
		(at 156.21 107.95 0)
		(unit 1)
		(exclude_from_sim no)
		(in_bom yes)
		(on_board yes)
		(dnp no)
		(property "Reference" "R221"
			(at 153.67 106.68 0)
			(effects
				(font
					(size 1.27 1.27)
				)
			)
		)
		(property "Value" "R_0R_0402"
			(at 156.21 111.76 0)
			(effects
				(font
					(size 1.27 1.27)
				)
				(justify left bottom)
				(hide yes)
			)
		)
		(property "Footprint" "antmicro-footprints:R_0402_1005Metric"
			(at 161.29 102.87 0)
			(effects
				(font
					(size 1.524 1.524)
				)
				(justify left bottom)
				(hide yes)
			)
		)
		(property "Datasheet" "https://industrial.panasonic.com/cdbs/www-data/pdf/RDA0000/AOA0000C301.pdf"
			(at 156.21 107.95 0)
			(effects
				(font
					(size 1.27 1.27)
				)
				(justify left bottom)
				(hide yes)
			)
		)
		(property "Description" ""
			(at 156.21 107.95 0)
			(effects
				(font
					(size 1.27 1.27)
				)
				(hide yes)
			)
		)
		(property "Manufacturer" "Panasonic"
			(at 161.29 97.79 0)
			(effects
				(font
					(size 1.524 1.524)
				)
				(justify left bottom)
				(hide yes)
			)
		)
		(property "MPN" "ERJ2GE0R00X"
			(at 161.29 100.33 0)
			(effects
				(font
					(size 1.524 1.524)
				)
				(justify left bottom)
				(hide yes)
			)
		)
		(property "Val" "0R"
			(at 162.56 106.68 0)
			(effects
				(font
					(size 1.27 1.27)
				)
			)
		)
		(property "License" "Apache-2.0"
			(at 176.53 133.35 0)
			(effects
				(font
					(size 1.27 1.27)
					(thickness 0.15)
				)
				(justify left bottom)
				(hide yes)
			)
		)
		(property "Author" "Antmicro"
			(at 176.53 135.89 0)
			(effects
				(font
					(size 1.27 1.27)
					(thickness 0.15)
				)
				(justify left bottom)
				(hide yes)
			)
		)
		(property "Tolerance" "~"
			(at 176.53 118.11 0)
			(effects
				(font
					(size 1.27 1.27)
				)
				(justify left bottom)
				(hide yes)
			)
		)
		(property "Current" "1A"
			(at 158.75 106.045 0)
			(effects
				(font
					(size 1.27 1.27)
					(thickness 0.15)
				)
				(hide yes)
			)
		)
		(pin "1"
		)
		(pin "2"
		)
		(instances
			(project "cm4-baseboard"
				(path ""
					(reference "R221")
					(unit 1)
				)
			)
		)
	)
	(symbol
		(lib_id "antmicropower:GND")
		(at 255.27 128.27 0)
		(unit 1)
		(exclude_from_sim no)
		(in_bom yes)
		(on_board yes)
		(dnp no)
		(fields_autoplaced yes)
		(property "Reference" "#PWR0239"
			(at 264.16 130.81 0)
			(effects
				(font
					(size 1.27 1.27)
					(thickness 0.15)
				)
				(justify left bottom)
				(hide yes)
			)
		)
		(property "Value" "GND"
			(at 255.27 132.715 0)
			(effects
				(font
					(size 1.27 1.27)
					(thickness 0.15)
				)
			)
		)
		(property "Footprint" ""
			(at 264.16 135.89 0)
			(effects
				(font
					(size 1.27 1.27)
					(thickness 0.15)
				)
				(justify left bottom)
				(hide yes)
			)
		)
		(property "Datasheet" ""
			(at 264.16 140.97 0)
			(effects
				(font
					(size 1.27 1.27)
					(thickness 0.15)
				)
				(justify left bottom)
				(hide yes)
			)
		)
		(property "Description" ""
			(at 255.27 128.27 0)
			(effects
				(font
					(size 1.27 1.27)
				)
				(hide yes)
			)
		)
		(property "Author" "Antmicro"
			(at 264.16 135.89 0)
			(effects
				(font
					(size 1.27 1.27)
					(thickness 0.15)
				)
				(justify left bottom)
				(hide yes)
			)
		)
		(property "License" "Apache-2.0"
			(at 264.16 138.43 0)
			(effects
				(font
					(size 1.27 1.27)
					(thickness 0.15)
				)
				(justify left bottom)
				(hide yes)
			)
		)
		(pin "1"
		)
		(instances
			(project "cm4-baseboard"
				(path ""
					(reference "#PWR0239")
					(unit 1)
				)
			)
		)
	)
	(symbol
		(lib_id "antmicroTransistorsFETsMOSFETsSingle:SSM3J332R")
		(at 44.45 227.33 270)
		(mirror x)
		(unit 1)
		(exclude_from_sim no)
		(in_bom yes)
		(on_board yes)
		(dnp no)
		(property "Reference" "Q204"
			(at 53.34 223.52 90)
			(effects
				(font
					(size 1.27 1.27)
					(thickness 0.15)
				)
			)
		)
		(property "Value" "SSM3J332R"
			(at 53.34 226.06 90)
			(effects
				(font
					(size 1.27 1.27)
					(thickness 0.15)
				)
				(hide yes)
			)
		)
		(property "Footprint" "antmicro-footprints:SOT-23-3"
			(at 39.37 213.36 0)
			(effects
				(font
					(size 1.27 1.27)
					(thickness 0.15)
				)
				(justify left bottom)
				(hide yes)
			)
		)
		(property "Datasheet" "https://www.mouser.com/datasheet/2/408/SSM3J332R_datasheet_en_20181015-1150575.pdf"
			(at 36.83 213.36 0)
			(effects
				(font
					(size 1.27 1.27)
					(thickness 0.15)
				)
				(justify left bottom)
				(hide yes)
			)
		)
		(property "Description" ""
			(at 44.45 227.33 0)
			(effects
				(font
					(size 1.27 1.27)
				)
				(hide yes)
			)
		)
		(property "MPN" "SSM3J332R,LF"
			(at 46.99 226.06 90)
			(effects
				(font
					(size 1.27 1.27)
					(thickness 0.15)
				)
				(justify left bottom)
			)
		)
		(property "Manufacturer" "Toshiba"
			(at 31.75 213.36 0)
			(effects
				(font
					(size 1.27 1.27)
					(thickness 0.15)
				)
				(justify left bottom)
				(hide yes)
			)
		)
		(property "Author" "Antmicro"
			(at 29.21 213.36 0)
			(effects
				(font
					(size 1.27 1.27)
					(thickness 0.15)
				)
				(justify left bottom)
				(hide yes)
			)
		)
		(property "License" "Apache-2.0"
			(at 26.67 213.36 0)
			(effects
				(font
					(size 1.27 1.27)
					(thickness 0.15)
				)
				(justify left bottom)
				(hide yes)
			)
		)
		(pin "1"
		)
		(pin "2"
		)
		(pin "3"
		)
		(instances
			(project "cm4-baseboard"
				(path ""
					(reference "Q204")
					(unit 1)
				)
			)
		)
	)
	(symbol
		(lib_id "antmicroCapacitors0402:C_100n_0402")
		(at 255.27 195.58 90)
		(unit 1)
		(exclude_from_sim no)
		(in_bom yes)
		(on_board yes)
		(dnp no)
		(property "Reference" "C203"
			(at 256.54 190.5 90)
			(effects
				(font
					(size 1.27 1.27)
					(thickness 0.15)
				)
				(justify right)
			)
		)
		(property "Value" "C_100n_0402"
			(at 265.43 175.26 0)
			(effects
				(font
					(size 1.27 1.27)
					(thickness 0.15)
				)
				(justify left bottom)
				(hide yes)
			)
		)
		(property "Footprint" "antmicro-footprints:C_0402_1005Metric"
			(at 267.97 175.26 0)
			(effects
				(font
					(size 1.27 1.27)
					(thickness 0.15)
				)
				(justify left bottom)
				(hide yes)
			)
		)
		(property "Datasheet" "https://www.murata.com/products/productdetail?partno=GRM155R61H104KE14%23"
			(at 270.51 175.26 0)
			(effects
				(font
					(size 1.27 1.27)
					(thickness 0.15)
				)
				(justify left bottom)
				(hide yes)
			)
		)
		(property "Description" ""
			(at 255.27 195.58 0)
			(effects
				(font
					(size 1.27 1.27)
				)
				(hide yes)
			)
		)
		(property "MPN" "GRM155R61H104KE14D"
			(at 273.05 175.26 0)
			(effects
				(font
					(size 1.27 1.27)
					(thickness 0.15)
				)
				(justify left bottom)
				(hide yes)
			)
		)
		(property "Manufacturer" "Murata"
			(at 275.59 175.26 0)
			(effects
				(font
					(size 1.27 1.27)
					(thickness 0.15)
				)
				(justify left bottom)
				(hide yes)
			)
		)
		(property "License" "Apache-2.0"
			(at 278.13 175.26 0)
			(effects
				(font
					(size 1.27 1.27)
					(thickness 0.15)
				)
				(justify left bottom)
				(hide yes)
			)
		)
		(property "Author" "Antmicro"
			(at 280.67 175.26 0)
			(effects
				(font
					(size 1.27 1.27)
					(thickness 0.15)
				)
				(justify left bottom)
				(hide yes)
			)
		)
		(property "Val" "100n"
			(at 256.54 195.58 90)
			(effects
				(font
					(size 1.27 1.27)
					(thickness 0.15)
				)
				(justify right)
			)
		)
		(property "Voltage" "50V"
			(at 283.21 175.26 0)
			(effects
				(font
					(size 1.27 1.27)
				)
				(justify left bottom)
				(hide yes)
			)
		)
		(property "Dielectric" "X5R"
			(at 285.75 175.26 0)
			(effects
				(font
					(size 1.27 1.27)
				)
				(justify left bottom)
				(hide yes)
			)
		)
		(pin "1"
		)
		(pin "2"
		)
		(instances
			(project "cm4-baseboard"
				(path ""
					(reference "C203")
					(unit 1)
				)
			)
		)
	)
	(symbol
		(lib_id "antmicropower:GND")
		(at 247.65 76.2 0)
		(unit 1)
		(exclude_from_sim no)
		(in_bom yes)
		(on_board yes)
		(dnp no)
		(property "Reference" "#PWR0236"
			(at 256.54 78.74 0)
			(effects
				(font
					(size 1.27 1.27)
					(thickness 0.15)
				)
				(justify left bottom)
				(hide yes)
			)
		)
		(property "Value" "GND"
			(at 247.65 80.01 0)
			(effects
				(font
					(size 1.27 1.27)
					(thickness 0.15)
				)
			)
		)
		(property "Footprint" ""
			(at 256.54 83.82 0)
			(effects
				(font
					(size 1.27 1.27)
					(thickness 0.15)
				)
				(justify left bottom)
				(hide yes)
			)
		)
		(property "Datasheet" ""
			(at 256.54 88.9 0)
			(effects
				(font
					(size 1.27 1.27)
					(thickness 0.15)
				)
				(justify left bottom)
				(hide yes)
			)
		)
		(property "Description" ""
			(at 247.65 76.2 0)
			(effects
				(font
					(size 1.27 1.27)
				)
				(hide yes)
			)
		)
		(property "Author" "Antmicro"
			(at 256.54 83.82 0)
			(effects
				(font
					(size 1.27 1.27)
					(thickness 0.15)
				)
				(justify left bottom)
				(hide yes)
			)
		)
		(property "License" "Apache-2.0"
			(at 256.54 86.36 0)
			(effects
				(font
					(size 1.27 1.27)
					(thickness 0.15)
				)
				(justify left bottom)
				(hide yes)
			)
		)
		(pin "1"
		)
		(instances
			(project "cm4-baseboard"
				(path ""
					(reference "#PWR0236")
					(unit 1)
				)
			)
		)
	)
	(symbol
		(lib_id "antmicroTestPoints:TP_0.75mm_SMD")
		(at 44.45 52.07 180)
		(unit 1)
		(exclude_from_sim no)
		(in_bom no)
		(on_board yes)
		(dnp no)
		(property "Reference" "TP203"
			(at 34.29 52.07 0)
			(effects
				(font
					(size 1.27 1.27)
					(thickness 0.15)
				)
				(justify right)
			)
		)
		(property "Value" "TP_0.75mm_SMD"
			(at 29.21 44.45 0)
			(effects
				(font
					(size 1.27 1.27)
					(thickness 0.15)
				)
				(justify left bottom)
				(hide yes)
			)
		)
		(property "Footprint" "antmicro-footprints:TP_SMD_0.75mm"
			(at 33.655 45.72 0)
			(effects
				(font
					(size 1.27 1.27)
					(thickness 0.15)
				)
				(justify left bottom)
				(hide yes)
			)
		)
		(property "Datasheet" ""
			(at 26.67 39.37 0)
			(effects
				(font
					(size 1.27 1.27)
					(thickness 0.15)
				)
				(justify left bottom)
				(hide yes)
			)
		)
		(property "Description" ""
			(at 44.45 52.07 0)
			(effects
				(font
					(size 1.27 1.27)
				)
				(hide yes)
			)
		)
		(property "Author" "Antmicro"
			(at 33.655 43.18 0)
			(effects
				(font
					(size 1.27 1.27)
					(thickness 0.15)
				)
				(justify left bottom)
				(hide yes)
			)
		)
		(property "License" "Apache-2.0"
			(at 33.655 40.64 0)
			(effects
				(font
					(size 1.27 1.27)
					(thickness 0.15)
				)
				(justify left bottom)
				(hide yes)
			)
		)
		(property "MPN" ""
			(at 33.655 40.64 0)
			(effects
				(font
					(size 1.27 1.27)
					(thickness 0.15)
				)
				(justify left bottom)
				(hide yes)
			)
		)
		(property "Manufacturer" ""
			(at 33.655 45.72 0)
			(effects
				(font
					(size 1.27 1.27)
					(thickness 0.15)
				)
				(justify left bottom)
				(hide yes)
			)
		)
		(pin "1"
		)
		(instances
			(project "cm4-baseboard"
				(path ""
					(reference "TP203")
					(unit 1)
				)
			)
		)
	)
	(symbol
		(lib_id "antmicropower:GND")
		(at 271.78 240.03 0)
		(unit 1)
		(exclude_from_sim no)
		(in_bom yes)
		(on_board yes)
		(dnp no)
		(property "Reference" "#PWR0250"
			(at 280.67 242.57 0)
			(effects
				(font
					(size 1.27 1.27)
					(thickness 0.15)
				)
				(justify left bottom)
				(hide yes)
			)
		)
		(property "Value" "GND"
			(at 271.78 244.475 0)
			(effects
				(font
					(size 1.27 1.27)
					(thickness 0.15)
				)
			)
		)
		(property "Footprint" ""
			(at 280.67 247.65 0)
			(effects
				(font
					(size 1.27 1.27)
					(thickness 0.15)
				)
				(justify left bottom)
				(hide yes)
			)
		)
		(property "Datasheet" ""
			(at 280.67 252.73 0)
			(effects
				(font
					(size 1.27 1.27)
					(thickness 0.15)
				)
				(justify left bottom)
				(hide yes)
			)
		)
		(property "Description" ""
			(at 271.78 240.03 0)
			(effects
				(font
					(size 1.27 1.27)
				)
				(hide yes)
			)
		)
		(property "Author" "Antmicro"
			(at 280.67 247.65 0)
			(effects
				(font
					(size 1.27 1.27)
					(thickness 0.15)
				)
				(justify left bottom)
				(hide yes)
			)
		)
		(property "License" "Apache-2.0"
			(at 280.67 250.19 0)
			(effects
				(font
					(size 1.27 1.27)
					(thickness 0.15)
				)
				(justify left bottom)
				(hide yes)
			)
		)
		(pin "1"
		)
		(instances
			(project "cm4-baseboard"
				(path ""
					(reference "#PWR0250")
					(unit 1)
				)
			)
		)
	)
	(symbol
		(lib_id "antmicropower:GND")
		(at 139.7 279.4 0)
		(unit 1)
		(exclude_from_sim no)
		(in_bom yes)
		(on_board yes)
		(dnp no)
		(fields_autoplaced yes)
		(property "Reference" "#PWR0220"
			(at 148.59 281.94 0)
			(effects
				(font
					(size 1.27 1.27)
					(thickness 0.15)
				)
				(justify left bottom)
				(hide yes)
			)
		)
		(property "Value" "GND"
			(at 137.6898 284.48 0)
			(effects
				(font
					(size 1.27 1.27)
					(thickness 0.15)
				)
				(justify left bottom)
			)
		)
		(property "Footprint" ""
			(at 148.59 287.02 0)
			(effects
				(font
					(size 1.27 1.27)
					(thickness 0.15)
				)
				(justify left bottom)
				(hide yes)
			)
		)
		(property "Datasheet" ""
			(at 148.59 292.1 0)
			(effects
				(font
					(size 1.27 1.27)
					(thickness 0.15)
				)
				(justify left bottom)
				(hide yes)
			)
		)
		(property "Description" ""
			(at 139.7 279.4 0)
			(effects
				(font
					(size 1.27 1.27)
				)
				(hide yes)
			)
		)
		(property "Author" "Antmicro"
			(at 148.59 287.02 0)
			(effects
				(font
					(size 1.27 1.27)
					(thickness 0.15)
				)
				(justify left bottom)
				(hide yes)
			)
		)
		(property "License" "Apache-2.0"
			(at 148.59 289.56 0)
			(effects
				(font
					(size 1.27 1.27)
					(thickness 0.15)
				)
				(justify left bottom)
				(hide yes)
			)
		)
		(pin "1"
		)
		(instances
			(project "cm4-baseboard"
				(path ""
					(reference "#PWR0220")
					(unit 1)
				)
			)
		)
	)
	(symbol
		(lib_id "antmicroResistors0402:R_200R_0402")
		(at 306.07 34.29 90)
		(unit 1)
		(exclude_from_sim no)
		(in_bom no)
		(on_board yes)
		(dnp yes)
		(fields_autoplaced yes)
		(property "Reference" "R242"
			(at 308.61 30.48 90)
			(effects
				(font
					(size 1.27 1.27)
				)
				(justify right)
			)
		)
		(property "Value" "R_200R_0402"
			(at 318.77 13.97 0)
			(effects
				(font
					(size 1.27 1.27)
					(thickness 0.15)
				)
				(justify left bottom)
				(hide yes)
			)
		)
		(property "Footprint" "antmicro-footprints:R_0402_1005Metric"
			(at 321.31 13.97 0)
			(effects
				(font
					(size 1.27 1.27)
					(thickness 0.15)
				)
				(justify left bottom)
				(hide yes)
			)
		)
		(property "Datasheet" "https://www.bourns.com/docs/product-datasheets/cr.pdf"
			(at 323.85 13.97 0)
			(effects
				(font
					(size 1.27 1.27)
					(thickness 0.15)
				)
				(justify left bottom)
				(hide yes)
			)
		)
		(property "Description" ""
			(at 306.07 34.29 0)
			(effects
				(font
					(size 1.27 1.27)
				)
				(hide yes)
			)
		)
		(property "Manufacturer" "Bourns"
			(at 328.93 13.97 0)
			(effects
				(font
					(size 1.27 1.27)
					(thickness 0.15)
				)
				(justify left bottom)
				(hide yes)
			)
		)
		(property "MPN" "CR0402-FX-2000GLF"
			(at 326.39 13.97 0)
			(effects
				(font
					(size 1.27 1.27)
					(thickness 0.15)
				)
				(justify left bottom)
				(hide yes)
			)
		)
		(property "Val" "200R"
			(at 308.61 33.02 90)
			(effects
				(font
					(size 1.27 1.27)
					(thickness 0.15)
				)
				(justify right)
			)
		)
		(property "License" "Apache-2.0"
			(at 331.47 13.97 0)
			(effects
				(font
					(size 1.27 1.27)
					(thickness 0.15)
				)
				(justify left bottom)
				(hide yes)
			)
		)
		(property "Author" "Antmicro"
			(at 334.01 13.97 0)
			(effects
				(font
					(size 1.27 1.27)
					(thickness 0.15)
				)
				(justify left bottom)
				(hide yes)
			)
		)
		(property "Tolerance" "1%"
			(at 316.23 13.97 0)
			(effects
				(font
					(size 1.27 1.27)
				)
				(justify left bottom)
				(hide yes)
			)
		)
		(pin "1"
		)
		(pin "2"
		)
		(instances
			(project "cm4-baseboard"
				(path ""
					(reference "R242")
					(unit 1)
				)
			)
		)
	)
	(symbol
		(lib_id "antmicropower:GND")
		(at 35.56 259.08 0)
		(unit 1)
		(exclude_from_sim no)
		(in_bom yes)
		(on_board yes)
		(dnp no)
		(property "Reference" "#PWR0202"
			(at 44.45 261.62 0)
			(effects
				(font
					(size 1.27 1.27)
					(thickness 0.15)
				)
				(justify left bottom)
				(hide yes)
			)
		)
		(property "Value" "GND"
			(at 35.56 262.89 0)
			(effects
				(font
					(size 1.27 1.27)
					(thickness 0.15)
				)
			)
		)
		(property "Footprint" ""
			(at 44.45 266.7 0)
			(effects
				(font
					(size 1.27 1.27)
					(thickness 0.15)
				)
				(justify left bottom)
				(hide yes)
			)
		)
		(property "Datasheet" ""
			(at 44.45 271.78 0)
			(effects
				(font
					(size 1.27 1.27)
					(thickness 0.15)
				)
				(justify left bottom)
				(hide yes)
			)
		)
		(property "Description" ""
			(at 35.56 259.08 0)
			(effects
				(font
					(size 1.27 1.27)
				)
				(hide yes)
			)
		)
		(property "Author" "Antmicro"
			(at 44.45 266.7 0)
			(effects
				(font
					(size 1.27 1.27)
					(thickness 0.15)
				)
				(justify left bottom)
				(hide yes)
			)
		)
		(property "License" "Apache-2.0"
			(at 44.45 269.24 0)
			(effects
				(font
					(size 1.27 1.27)
					(thickness 0.15)
				)
				(justify left bottom)
				(hide yes)
			)
		)
		(pin "1"
		)
		(instances
			(project "cm4-baseboard"
				(path ""
					(reference "#PWR0202")
					(unit 1)
				)
			)
		)
	)
	(symbol
		(lib_id "antmicroResistors0402:R_0R_0402")
		(at 210.82 195.58 0)
		(mirror x)
		(unit 1)
		(exclude_from_sim no)
		(in_bom yes)
		(on_board yes)
		(dnp no)
		(property "Reference" "R2"
			(at 209.55 196.85 0)
			(effects
				(font
					(size 1.27 1.27)
				)
			)
		)
		(property "Value" "R_0R_0402"
			(at 210.82 191.77 0)
			(effects
				(font
					(size 1.27 1.27)
				)
				(justify left bottom)
				(hide yes)
			)
		)
		(property "Footprint" "antmicro-footprints:R_0402_1005Metric"
			(at 215.9 200.66 0)
			(effects
				(font
					(size 1.524 1.524)
				)
				(justify left bottom)
				(hide yes)
			)
		)
		(property "Datasheet" "https://industrial.panasonic.com/cdbs/www-data/pdf/RDA0000/AOA0000C301.pdf"
			(at 210.82 195.58 0)
			(effects
				(font
					(size 1.27 1.27)
				)
				(justify left bottom)
				(hide yes)
			)
		)
		(property "Description" ""
			(at 210.82 195.58 0)
			(effects
				(font
					(size 1.27 1.27)
				)
				(hide yes)
			)
		)
		(property "Manufacturer" "Panasonic"
			(at 215.9 205.74 0)
			(effects
				(font
					(size 1.524 1.524)
				)
				(justify left bottom)
				(hide yes)
			)
		)
		(property "MPN" "ERJ2GE0R00X"
			(at 215.9 203.2 0)
			(effects
				(font
					(size 1.524 1.524)
				)
				(justify left bottom)
				(hide yes)
			)
		)
		(property "Val" "0R"
			(at 217.17 196.85 0)
			(effects
				(font
					(size 1.27 1.27)
				)
			)
		)
		(property "License" "Apache-2.0"
			(at 231.14 170.18 0)
			(effects
				(font
					(size 1.27 1.27)
					(thickness 0.15)
				)
				(justify left bottom)
				(hide yes)
			)
		)
		(property "Author" "Antmicro"
			(at 231.14 167.64 0)
			(effects
				(font
					(size 1.27 1.27)
					(thickness 0.15)
				)
				(justify left bottom)
				(hide yes)
			)
		)
		(property "Tolerance" "~"
			(at 231.14 185.42 0)
			(effects
				(font
					(size 1.27 1.27)
				)
				(justify left bottom)
				(hide yes)
			)
		)
		(property "Current" "1A"
			(at 213.36 197.485 0)
			(effects
				(font
					(size 1.27 1.27)
					(thickness 0.15)
				)
				(hide yes)
			)
		)
		(pin "1"
		)
		(pin "2"
		)
		(instances
			(project "cm4-baseboard"
				(path ""
					(reference "R2")
					(unit 1)
				)
			)
		)
	)
	(symbol
		(lib_id "antmicroCapacitors0402:C_100n_0402")
		(at 266.7 195.58 90)
		(unit 1)
		(exclude_from_sim no)
		(in_bom yes)
		(on_board yes)
		(dnp no)
		(property "Reference" "C206"
			(at 267.97 190.5 90)
			(effects
				(font
					(size 1.27 1.27)
					(thickness 0.15)
				)
				(justify right)
			)
		)
		(property "Value" "C_100n_0402"
			(at 276.86 175.26 0)
			(effects
				(font
					(size 1.27 1.27)
					(thickness 0.15)
				)
				(justify left bottom)
				(hide yes)
			)
		)
		(property "Footprint" "antmicro-footprints:C_0402_1005Metric"
			(at 279.4 175.26 0)
			(effects
				(font
					(size 1.27 1.27)
					(thickness 0.15)
				)
				(justify left bottom)
				(hide yes)
			)
		)
		(property "Datasheet" "https://www.murata.com/products/productdetail?partno=GRM155R61H104KE14%23"
			(at 281.94 175.26 0)
			(effects
				(font
					(size 1.27 1.27)
					(thickness 0.15)
				)
				(justify left bottom)
				(hide yes)
			)
		)
		(property "Description" ""
			(at 266.7 195.58 0)
			(effects
				(font
					(size 1.27 1.27)
				)
				(hide yes)
			)
		)
		(property "MPN" "GRM155R61H104KE14D"
			(at 284.48 175.26 0)
			(effects
				(font
					(size 1.27 1.27)
					(thickness 0.15)
				)
				(justify left bottom)
				(hide yes)
			)
		)
		(property "Manufacturer" "Murata"
			(at 287.02 175.26 0)
			(effects
				(font
					(size 1.27 1.27)
					(thickness 0.15)
				)
				(justify left bottom)
				(hide yes)
			)
		)
		(property "License" "Apache-2.0"
			(at 289.56 175.26 0)
			(effects
				(font
					(size 1.27 1.27)
					(thickness 0.15)
				)
				(justify left bottom)
				(hide yes)
			)
		)
		(property "Author" "Antmicro"
			(at 292.1 175.26 0)
			(effects
				(font
					(size 1.27 1.27)
					(thickness 0.15)
				)
				(justify left bottom)
				(hide yes)
			)
		)
		(property "Val" "100n"
			(at 267.97 195.58 90)
			(effects
				(font
					(size 1.27 1.27)
					(thickness 0.15)
				)
				(justify right)
			)
		)
		(property "Voltage" "50V"
			(at 294.64 175.26 0)
			(effects
				(font
					(size 1.27 1.27)
				)
				(justify left bottom)
				(hide yes)
			)
		)
		(property "Dielectric" "X5R"
			(at 297.18 175.26 0)
			(effects
				(font
					(size 1.27 1.27)
				)
				(justify left bottom)
				(hide yes)
			)
		)
		(pin "1"
		)
		(pin "2"
		)
		(instances
			(project "cm4-baseboard"
				(path ""
					(reference "C206")
					(unit 1)
				)
			)
		)
	)
	(symbol
		(lib_id "antmicroTestPoints:TP_0.75mm_SMD")
		(at 68.58 199.39 270)
		(unit 1)
		(exclude_from_sim no)
		(in_bom no)
		(on_board yes)
		(dnp no)
		(property "Reference" "TP214"
			(at 71.12 205.105 90)
			(effects
				(font
					(size 1.27 1.27)
				)
				(justify right)
			)
		)
		(property "Value" "TP_0.75mm_SMD"
			(at 66.04 199.39 0)
			(effects
				(font
					(size 1.27 1.27)
					(thickness 0.15)
				)
				(justify left bottom)
				(hide yes)
			)
		)
		(property "Footprint" "antmicro-footprints:TP_SMD_0.75mm"
			(at 73.66 204.47 0)
			(effects
				(font
					(size 1.27 1.27)
					(thickness 0.15)
				)
				(justify left bottom)
				(hide yes)
			)
		)
		(property "Datasheet" ""
			(at 76.2 204.47 0)
			(effects
				(font
					(size 1.27 1.27)
					(thickness 0.15)
				)
				(justify left bottom)
				(hide yes)
			)
		)
		(property "Description" ""
			(at 68.58 199.39 0)
			(effects
				(font
					(size 1.27 1.27)
				)
				(hide yes)
			)
		)
		(property "MPN" ""
			(at 68.58 199.39 0)
			(effects
				(font
					(size 1.27 1.27)
					(thickness 0.15)
				)
				(justify left bottom)
				(hide yes)
			)
		)
		(property "Manufacturer" ""
			(at 68.58 199.39 0)
			(effects
				(font
					(size 1.27 1.27)
					(thickness 0.15)
				)
				(justify left bottom)
				(hide yes)
			)
		)
		(property "Author" "Antmicro"
			(at 53.34 214.63 0)
			(effects
				(font
					(size 1.27 1.27)
					(thickness 0.15)
				)
				(justify left bottom)
				(hide yes)
			)
		)
		(property "License" "Apache-2.0"
			(at 50.8 214.63 0)
			(effects
				(font
					(size 1.27 1.27)
					(thickness 0.15)
				)
				(justify left bottom)
				(hide yes)
			)
		)
		(pin "1"
		)
		(instances
			(project "cm4-baseboard"
				(path ""
					(reference "TP214")
					(unit 1)
				)
			)
		)
	)
	(symbol
		(lib_id "antmicroResistors0402:R_470R_0402")
		(at 227.33 219.71 90)
		(unit 1)
		(exclude_from_sim no)
		(in_bom yes)
		(on_board yes)
		(dnp no)
		(property "Reference" "R210"
			(at 220.98 215.9 90)
			(effects
				(font
					(size 1.27 1.27)
				)
				(justify right)
			)
		)
		(property "Value" "R_470R_0402"
			(at 240.03 199.39 0)
			(effects
				(font
					(size 1.27 1.27)
					(thickness 0.15)
				)
				(justify left bottom)
				(hide yes)
			)
		)
		(property "Footprint" "antmicro-footprints:R_0402_1005Metric"
			(at 242.57 199.39 0)
			(effects
				(font
					(size 1.27 1.27)
					(thickness 0.15)
				)
				(justify left bottom)
				(hide yes)
			)
		)
		(property "Datasheet" "https://www.bourns.com/docs/product-datasheets/cr.pdf"
			(at 245.11 199.39 0)
			(effects
				(font
					(size 1.27 1.27)
					(thickness 0.15)
				)
				(justify left bottom)
				(hide yes)
			)
		)
		(property "Description" ""
			(at 227.33 219.71 0)
			(effects
				(font
					(size 1.27 1.27)
				)
				(hide yes)
			)
		)
		(property "Manufacturer" "Bourns"
			(at 250.19 199.39 0)
			(effects
				(font
					(size 1.27 1.27)
					(thickness 0.15)
				)
				(justify left bottom)
				(hide yes)
			)
		)
		(property "MPN" "CR0402-FX-4700GLF"
			(at 247.65 199.39 0)
			(effects
				(font
					(size 1.27 1.27)
					(thickness 0.15)
				)
				(justify left bottom)
				(hide yes)
			)
		)
		(property "Val" "470R"
			(at 220.98 218.44 90)
			(effects
				(font
					(size 1.27 1.27)
					(thickness 0.15)
				)
				(justify right)
			)
		)
		(property "License" "Apache-2.0"
			(at 252.73 199.39 0)
			(effects
				(font
					(size 1.27 1.27)
					(thickness 0.15)
				)
				(justify left bottom)
				(hide yes)
			)
		)
		(property "Author" "Antmicro"
			(at 255.27 199.39 0)
			(effects
				(font
					(size 1.27 1.27)
					(thickness 0.15)
				)
				(justify left bottom)
				(hide yes)
			)
		)
		(property "Tolerance" "1%"
			(at 237.49 199.39 0)
			(effects
				(font
					(size 1.27 1.27)
				)
				(justify left bottom)
				(hide yes)
			)
		)
		(pin "1"
		)
		(pin "2"
		)
		(instances
			(project "cm4-baseboard"
				(path ""
					(reference "R210")
					(unit 1)
				)
			)
		)
	)
	(symbol
		(lib_id "antmicropower:+3V3")
		(at 293.37 87.63 0)
		(unit 1)
		(exclude_from_sim no)
		(in_bom yes)
		(on_board yes)
		(dnp no)
		(fields_autoplaced yes)
		(property "Reference" "#PWR0260"
			(at 308.61 87.63 0)
			(effects
				(font
					(size 1.27 1.27)
					(thickness 0.15)
				)
				(justify left bottom)
				(hide yes)
			)
		)
		(property "Value" "+3V3"
			(at 293.37 82.55 0)
			(effects
				(font
					(size 1.27 1.27)
					(thickness 0.15)
				)
			)
		)
		(property "Footprint" ""
			(at 308.61 95.25 0)
			(effects
				(font
					(size 1.27 1.27)
					(thickness 0.15)
				)
				(justify left bottom)
				(hide yes)
			)
		)
		(property "Datasheet" ""
			(at 308.61 97.79 0)
			(effects
				(font
					(size 1.27 1.27)
					(thickness 0.15)
				)
				(justify left bottom)
				(hide yes)
			)
		)
		(property "Description" ""
			(at 293.37 87.63 0)
			(effects
				(font
					(size 1.27 1.27)
				)
				(hide yes)
			)
		)
		(property "Author" "Antmicro"
			(at 308.61 90.17 0)
			(effects
				(font
					(size 1.27 1.27)
					(thickness 0.15)
				)
				(justify left bottom)
				(hide yes)
			)
		)
		(property "License" "Apache-2.0"
			(at 308.61 92.71 0)
			(effects
				(font
					(size 1.27 1.27)
					(thickness 0.15)
				)
				(justify left bottom)
				(hide yes)
			)
		)
		(pin "1"
		)
		(instances
			(project "cm4-baseboard"
				(path ""
					(reference "#PWR0260")
					(unit 1)
				)
			)
		)
	)
	(symbol
		(lib_id "antmicroResistors0402:R_0R_0402")
		(at 189.23 255.27 0)
		(unit 1)
		(exclude_from_sim no)
		(in_bom yes)
		(on_board yes)
		(dnp no)
		(property "Reference" "R259"
			(at 186.69 254 0)
			(effects
				(font
					(size 1.27 1.27)
				)
			)
		)
		(property "Value" "R_0R_0402"
			(at 189.23 259.08 0)
			(effects
				(font
					(size 1.27 1.27)
				)
				(justify left bottom)
				(hide yes)
			)
		)
		(property "Footprint" "antmicro-footprints:R_0402_1005Metric"
			(at 194.31 250.19 0)
			(effects
				(font
					(size 1.524 1.524)
				)
				(justify left bottom)
				(hide yes)
			)
		)
		(property "Datasheet" "https://industrial.panasonic.com/cdbs/www-data/pdf/RDA0000/AOA0000C301.pdf"
			(at 189.23 255.27 0)
			(effects
				(font
					(size 1.27 1.27)
				)
				(justify left bottom)
				(hide yes)
			)
		)
		(property "Description" ""
			(at 189.23 255.27 0)
			(effects
				(font
					(size 1.27 1.27)
				)
				(hide yes)
			)
		)
		(property "Manufacturer" "Panasonic"
			(at 194.31 245.11 0)
			(effects
				(font
					(size 1.524 1.524)
				)
				(justify left bottom)
				(hide yes)
			)
		)
		(property "MPN" "ERJ2GE0R00X"
			(at 194.31 247.65 0)
			(effects
				(font
					(size 1.524 1.524)
				)
				(justify left bottom)
				(hide yes)
			)
		)
		(property "Val" "0R"
			(at 195.58 254 0)
			(effects
				(font
					(size 1.27 1.27)
				)
			)
		)
		(property "License" "Apache-2.0"
			(at 209.55 280.67 0)
			(effects
				(font
					(size 1.27 1.27)
					(thickness 0.15)
				)
				(justify left bottom)
				(hide yes)
			)
		)
		(property "Author" "Antmicro"
			(at 209.55 283.21 0)
			(effects
				(font
					(size 1.27 1.27)
					(thickness 0.15)
				)
				(justify left bottom)
				(hide yes)
			)
		)
		(property "Tolerance" "~"
			(at 209.55 265.43 0)
			(effects
				(font
					(size 1.27 1.27)
				)
				(justify left bottom)
				(hide yes)
			)
		)
		(property "Current" "1A"
			(at 191.77 253.365 0)
			(effects
				(font
					(size 1.27 1.27)
					(thickness 0.15)
				)
				(hide yes)
			)
		)
		(pin "1"
		)
		(pin "2"
		)
		(instances
			(project "cm4-baseboard"
				(path ""
					(reference "R259")
					(unit 1)
				)
			)
		)
	)
	(symbol
		(lib_id "antmicroTransistorsFETsMOSFETsSingle:SSM3J332R")
		(at 358.14 224.79 270)
		(mirror x)
		(unit 1)
		(exclude_from_sim no)
		(in_bom yes)
		(on_board yes)
		(dnp no)
		(fields_autoplaced yes)
		(property "Reference" "Q212"
			(at 360.68 210.82 90)
			(effects
				(font
					(size 1.27 1.27)
					(thickness 0.15)
				)
			)
		)
		(property "Value" "SSM3J332R"
			(at 367.03 223.52 90)
			(effects
				(font
					(size 1.27 1.27)
					(thickness 0.15)
				)
				(hide yes)
			)
		)
		(property "Footprint" "antmicro-footprints:SOT-23-3"
			(at 353.06 210.82 0)
			(effects
				(font
					(size 1.27 1.27)
					(thickness 0.15)
				)
				(justify left bottom)
				(hide yes)
			)
		)
		(property "Datasheet" "https://www.mouser.com/datasheet/2/408/SSM3J332R_datasheet_en_20181015-1150575.pdf"
			(at 350.52 210.82 0)
			(effects
				(font
					(size 1.27 1.27)
					(thickness 0.15)
				)
				(justify left bottom)
				(hide yes)
			)
		)
		(property "Description" ""
			(at 358.14 224.79 0)
			(effects
				(font
					(size 1.27 1.27)
				)
				(hide yes)
			)
		)
		(property "MPN" "SSM3J332R,LF"
			(at 360.68 213.36 90)
			(effects
				(font
					(size 1.27 1.27)
					(thickness 0.15)
				)
			)
		)
		(property "Manufacturer" "Toshiba"
			(at 345.44 210.82 0)
			(effects
				(font
					(size 1.27 1.27)
					(thickness 0.15)
				)
				(justify left bottom)
				(hide yes)
			)
		)
		(property "Author" "Antmicro"
			(at 342.9 210.82 0)
			(effects
				(font
					(size 1.27 1.27)
					(thickness 0.15)
				)
				(justify left bottom)
				(hide yes)
			)
		)
		(property "License" "Apache-2.0"
			(at 340.36 210.82 0)
			(effects
				(font
					(size 1.27 1.27)
					(thickness 0.15)
				)
				(justify left bottom)
				(hide yes)
			)
		)
		(pin "1"
		)
		(pin "2"
		)
		(pin "3"
		)
		(instances
			(project "cm4-baseboard"
				(path ""
					(reference "Q212")
					(unit 1)
				)
			)
		)
	)
	(symbol
		(lib_id "antmicroResistors0402:R_0R_0402")
		(at 86.36 125.73 180)
		(unit 1)
		(exclude_from_sim no)
		(in_bom no)
		(on_board yes)
		(dnp yes)
		(property "Reference" "R244"
			(at 82.55 121.92 0)
			(effects
				(font
					(size 1.27 1.27)
				)
			)
		)
		(property "Value" "R_0R_0402"
			(at 86.36 121.92 0)
			(effects
				(font
					(size 1.27 1.27)
				)
				(justify left bottom)
				(hide yes)
			)
		)
		(property "Footprint" "antmicro-footprints:R_0402_1005Metric"
			(at 81.28 130.81 0)
			(effects
				(font
					(size 1.524 1.524)
				)
				(justify left bottom)
				(hide yes)
			)
		)
		(property "Datasheet" "https://industrial.panasonic.com/cdbs/www-data/pdf/RDA0000/AOA0000C301.pdf"
			(at 86.36 125.73 0)
			(effects
				(font
					(size 1.27 1.27)
				)
				(justify left bottom)
				(hide yes)
			)
		)
		(property "Description" ""
			(at 86.36 125.73 0)
			(effects
				(font
					(size 1.27 1.27)
				)
				(hide yes)
			)
		)
		(property "Manufacturer" "Panasonic"
			(at 81.28 135.89 0)
			(effects
				(font
					(size 1.524 1.524)
				)
				(justify left bottom)
				(hide yes)
			)
		)
		(property "MPN" "ERJ2GE0R00X"
			(at 81.28 133.35 0)
			(effects
				(font
					(size 1.524 1.524)
				)
				(justify left bottom)
				(hide yes)
			)
		)
		(property "Val" "0R"
			(at 82.55 123.825 0)
			(effects
				(font
					(size 1.27 1.27)
				)
			)
		)
		(property "License" "Apache-2.0"
			(at 66.04 100.33 0)
			(effects
				(font
					(size 1.27 1.27)
					(thickness 0.15)
				)
				(justify left bottom)
				(hide yes)
			)
		)
		(property "Author" "Antmicro"
			(at 66.04 97.79 0)
			(effects
				(font
					(size 1.27 1.27)
					(thickness 0.15)
				)
				(justify left bottom)
				(hide yes)
			)
		)
		(property "Tolerance" "~"
			(at 66.04 115.57 0)
			(effects
				(font
					(size 1.27 1.27)
				)
				(justify left bottom)
				(hide yes)
			)
		)
		(property "Current" "1A"
			(at 83.82 127.635 0)
			(effects
				(font
					(size 1.27 1.27)
					(thickness 0.15)
				)
				(hide yes)
			)
		)
		(pin "1"
		)
		(pin "2"
		)
		(instances
			(project "cm4-baseboard"
				(path ""
					(reference "R244")
					(unit 1)
				)
			)
		)
	)
	(symbol
		(lib_id "antmicroResistors0402:R_10k_0402")
		(at 247.65 74.93 270)
		(mirror x)
		(unit 1)
		(exclude_from_sim no)
		(in_bom yes)
		(on_board yes)
		(dnp no)
		(property "Reference" "R233"
			(at 246.38 71.12 90)
			(effects
				(font
					(size 1.27 1.27)
					(thickness 0.15)
				)
				(justify right)
			)
		)
		(property "Value" "R_10k_0402"
			(at 234.95 54.61 0)
			(effects
				(font
					(size 1.27 1.27)
					(thickness 0.15)
				)
				(justify left bottom)
				(hide yes)
			)
		)
		(property "Footprint" "antmicro-footprints:R_0402_1005Metric"
			(at 232.41 54.61 0)
			(effects
				(font
					(size 1.27 1.27)
					(thickness 0.15)
				)
				(justify left bottom)
				(hide yes)
			)
		)
		(property "Datasheet" "https://www.bourns.com/docs/product-datasheets/cr.pdf"
			(at 229.87 54.61 0)
			(effects
				(font
					(size 1.27 1.27)
					(thickness 0.15)
				)
				(justify left bottom)
				(hide yes)
			)
		)
		(property "Description" ""
			(at 247.65 74.93 0)
			(effects
				(font
					(size 1.27 1.27)
				)
				(hide yes)
			)
		)
		(property "MPN" "CR0402-FX-1002GLF"
			(at 227.33 54.61 0)
			(effects
				(font
					(size 1.27 1.27)
					(thickness 0.15)
				)
				(justify left bottom)
				(hide yes)
			)
		)
		(property "Manufacturer" "Bourns"
			(at 224.79 54.61 0)
			(effects
				(font
					(size 1.27 1.27)
					(thickness 0.15)
				)
				(justify left bottom)
				(hide yes)
			)
		)
		(property "License" "Apache-2.0"
			(at 222.25 54.61 0)
			(effects
				(font
					(size 1.27 1.27)
					(thickness 0.15)
				)
				(justify left bottom)
				(hide yes)
			)
		)
		(property "Author" "Antmicro"
			(at 219.71 54.61 0)
			(effects
				(font
					(size 1.27 1.27)
					(thickness 0.15)
				)
				(justify left bottom)
				(hide yes)
			)
		)
		(property "Val" "10k"
			(at 246.38 73.66 90)
			(effects
				(font
					(size 1.27 1.27)
					(thickness 0.15)
				)
				(justify right)
			)
		)
		(property "Tolerance" "1%"
			(at 237.49 54.61 0)
			(effects
				(font
					(size 1.27 1.27)
				)
				(justify left bottom)
				(hide yes)
			)
		)
		(pin "1"
		)
		(pin "2"
		)
		(instances
			(project "cm4-baseboard"
				(path ""
					(reference "R233")
					(unit 1)
				)
			)
		)
	)
	(symbol
		(lib_id "antmicropower:GND")
		(at 255.27 76.2 0)
		(unit 1)
		(exclude_from_sim no)
		(in_bom yes)
		(on_board yes)
		(dnp no)
		(property "Reference" "#PWR0241"
			(at 264.16 78.74 0)
			(effects
				(font
					(size 1.27 1.27)
					(thickness 0.15)
				)
				(justify left bottom)
				(hide yes)
			)
		)
		(property "Value" "GND"
			(at 255.27 80.01 0)
			(effects
				(font
					(size 1.27 1.27)
					(thickness 0.15)
				)
			)
		)
		(property "Footprint" ""
			(at 264.16 83.82 0)
			(effects
				(font
					(size 1.27 1.27)
					(thickness 0.15)
				)
				(justify left bottom)
				(hide yes)
			)
		)
		(property "Datasheet" ""
			(at 264.16 88.9 0)
			(effects
				(font
					(size 1.27 1.27)
					(thickness 0.15)
				)
				(justify left bottom)
				(hide yes)
			)
		)
		(property "Description" ""
			(at 255.27 76.2 0)
			(effects
				(font
					(size 1.27 1.27)
				)
				(hide yes)
			)
		)
		(property "Author" "Antmicro"
			(at 264.16 83.82 0)
			(effects
				(font
					(size 1.27 1.27)
					(thickness 0.15)
				)
				(justify left bottom)
				(hide yes)
			)
		)
		(property "License" "Apache-2.0"
			(at 264.16 86.36 0)
			(effects
				(font
					(size 1.27 1.27)
					(thickness 0.15)
				)
				(justify left bottom)
				(hide yes)
			)
		)
		(pin "1"
		)
		(instances
			(project "cm4-baseboard"
				(path ""
					(reference "#PWR0241")
					(unit 1)
				)
			)
		)
	)
	(symbol
		(lib_id "antmicroTestPoints:TP_0.75mm_SMD")
		(at 306.07 73.66 0)
		(mirror x)
		(unit 1)
		(exclude_from_sim no)
		(in_bom no)
		(on_board yes)
		(dnp no)
		(property "Reference" "TP211"
			(at 313.055 73.66 0)
			(effects
				(font
					(size 1.27 1.27)
					(thickness 0.15)
				)
			)
		)
		(property "Value" "TP_0.75mm_SMD"
			(at 321.31 66.04 0)
			(effects
				(font
					(size 1.27 1.27)
					(thickness 0.15)
				)
				(justify left bottom)
				(hide yes)
			)
		)
		(property "Footprint" "antmicro-footprints:TP_SMD_0.75mm"
			(at 316.865 67.31 0)
			(effects
				(font
					(size 1.27 1.27)
					(thickness 0.15)
				)
				(justify left bottom)
				(hide yes)
			)
		)
		(property "Datasheet" ""
			(at 323.85 60.96 0)
			(effects
				(font
					(size 1.27 1.27)
					(thickness 0.15)
				)
				(justify left bottom)
				(hide yes)
			)
		)
		(property "Description" ""
			(at 306.07 73.66 0)
			(effects
				(font
					(size 1.27 1.27)
				)
				(hide yes)
			)
		)
		(property "Author" "Antmicro"
			(at 316.865 64.77 0)
			(effects
				(font
					(size 1.27 1.27)
					(thickness 0.15)
				)
				(justify left bottom)
				(hide yes)
			)
		)
		(property "License" "Apache-2.0"
			(at 316.865 62.23 0)
			(effects
				(font
					(size 1.27 1.27)
					(thickness 0.15)
				)
				(justify left bottom)
				(hide yes)
			)
		)
		(property "MPN" ""
			(at 316.865 62.23 0)
			(effects
				(font
					(size 1.27 1.27)
					(thickness 0.15)
				)
				(justify left bottom)
				(hide yes)
			)
		)
		(property "Manufacturer" ""
			(at 316.865 67.31 0)
			(effects
				(font
					(size 1.27 1.27)
					(thickness 0.15)
				)
				(justify left bottom)
				(hide yes)
			)
		)
		(pin "1"
		)
		(instances
			(project "cm4-baseboard"
				(path ""
					(reference "TP211")
					(unit 1)
				)
			)
		)
	)
	(symbol
		(lib_id "antmicroTransistorsFETsMOSFETsSingle:PJE138K")
		(at 190.5 215.9 0)
		(unit 1)
		(exclude_from_sim no)
		(in_bom yes)
		(on_board yes)
		(dnp no)
		(property "Reference" "Q214"
			(at 199.39 213.36 0)
			(effects
				(font
					(size 1.27 1.27)
					(thickness 0.15)
				)
				(justify left)
			)
		)
		(property "Value" "PJE138K"
			(at 199.39 215.9 0)
			(effects
				(font
					(size 1.27 1.27)
					(thickness 0.15)
				)
				(justify left)
			)
		)
		(property "Footprint" "antmicro-footprints:SOT-523"
			(at 213.36 227.33 0)
			(effects
				(font
					(size 1.27 1.27)
					(thickness 0.15)
				)
				(justify left bottom)
				(hide yes)
			)
		)
		(property "Datasheet" "https://www.mouser.com/datasheet/2/1057/PJE138K-1876698.pdf"
			(at 213.36 229.87 0)
			(effects
				(font
					(size 1.27 1.27)
					(thickness 0.15)
				)
				(justify left bottom)
				(hide yes)
			)
		)
		(property "Description" ""
			(at 190.5 215.9 0)
			(effects
				(font
					(size 1.27 1.27)
				)
				(hide yes)
			)
		)
		(property "MPN" "PJE138K_R1_00001"
			(at 213.36 232.41 0)
			(effects
				(font
					(size 1.27 1.27)
					(thickness 0.15)
				)
				(justify left bottom)
				(hide yes)
			)
		)
		(property "Manufacturer" "PANJIT"
			(at 213.36 234.95 0)
			(effects
				(font
					(size 1.27 1.27)
					(thickness 0.15)
				)
				(justify left bottom)
				(hide yes)
			)
		)
		(property "Author" "Antmicro"
			(at 213.36 237.49 0)
			(effects
				(font
					(size 1.27 1.27)
					(thickness 0.15)
				)
				(justify left bottom)
				(hide yes)
			)
		)
		(property "License" "Apache-2.0"
			(at 213.36 240.03 0)
			(effects
				(font
					(size 1.27 1.27)
					(thickness 0.15)
				)
				(justify left bottom)
				(hide yes)
			)
		)
		(pin "1"
		)
		(pin "2"
		)
		(pin "3"
		)
		(instances
			(project "cm4-baseboard"
				(path ""
					(reference "Q214")
					(unit 1)
				)
			)
		)
	)
	(symbol
		(lib_id "antmicropower:+3V3")
		(at 266.7 120.65 0)
		(unit 1)
		(exclude_from_sim no)
		(in_bom yes)
		(on_board yes)
		(dnp no)
		(fields_autoplaced yes)
		(property "Reference" "#PWR0253"
			(at 281.94 123.19 0)
			(effects
				(font
					(size 1.27 1.27)
					(thickness 0.15)
				)
				(justify left bottom)
				(hide yes)
			)
		)
		(property "Value" "+3V3"
			(at 266.065 116.84 0)
			(effects
				(font
					(size 1.27 1.27)
					(thickness 0.15)
				)
			)
		)
		(property "Footprint" ""
			(at 281.94 128.27 0)
			(effects
				(font
					(size 1.27 1.27)
					(thickness 0.15)
				)
				(justify left bottom)
				(hide yes)
			)
		)
		(property "Datasheet" ""
			(at 281.94 130.81 0)
			(effects
				(font
					(size 1.27 1.27)
					(thickness 0.15)
				)
				(justify left bottom)
				(hide yes)
			)
		)
		(property "Description" ""
			(at 266.7 120.65 0)
			(effects
				(font
					(size 1.27 1.27)
				)
				(hide yes)
			)
		)
		(property "Author" "Antmicro"
			(at 281.94 128.27 0)
			(effects
				(font
					(size 1.27 1.27)
					(thickness 0.15)
				)
				(justify left bottom)
				(hide yes)
			)
		)
		(property "License" "Apache-2.0"
			(at 281.94 130.81 0)
			(effects
				(font
					(size 1.27 1.27)
					(thickness 0.15)
				)
				(justify left bottom)
				(hide yes)
			)
		)
		(pin "1"
		)
		(instances
			(project "cm4-baseboard"
				(path ""
					(reference "#PWR0253")
					(unit 1)
				)
			)
		)
	)
	(symbol
		(lib_id "antmicropower:GND")
		(at 240.03 76.2 0)
		(unit 1)
		(exclude_from_sim no)
		(in_bom yes)
		(on_board yes)
		(dnp no)
		(property "Reference" "#PWR0233"
			(at 248.92 78.74 0)
			(effects
				(font
					(size 1.27 1.27)
					(thickness 0.15)
				)
				(justify left bottom)
				(hide yes)
			)
		)
		(property "Value" "GND"
			(at 240.03 80.01 0)
			(effects
				(font
					(size 1.27 1.27)
					(thickness 0.15)
				)
			)
		)
		(property "Footprint" ""
			(at 248.92 83.82 0)
			(effects
				(font
					(size 1.27 1.27)
					(thickness 0.15)
				)
				(justify left bottom)
				(hide yes)
			)
		)
		(property "Datasheet" ""
			(at 248.92 88.9 0)
			(effects
				(font
					(size 1.27 1.27)
					(thickness 0.15)
				)
				(justify left bottom)
				(hide yes)
			)
		)
		(property "Description" ""
			(at 240.03 76.2 0)
			(effects
				(font
					(size 1.27 1.27)
				)
				(hide yes)
			)
		)
		(property "Author" "Antmicro"
			(at 248.92 83.82 0)
			(effects
				(font
					(size 1.27 1.27)
					(thickness 0.15)
				)
				(justify left bottom)
				(hide yes)
			)
		)
		(property "License" "Apache-2.0"
			(at 248.92 86.36 0)
			(effects
				(font
					(size 1.27 1.27)
					(thickness 0.15)
				)
				(justify left bottom)
				(hide yes)
			)
		)
		(pin "1"
		)
		(instances
			(project "cm4-baseboard"
				(path ""
					(reference "#PWR0233")
					(unit 1)
				)
			)
		)
	)
	(symbol
		(lib_id "antmicroResistors0402:R_0R_0402")
		(at 156.21 92.71 0)
		(unit 1)
		(exclude_from_sim no)
		(in_bom yes)
		(on_board yes)
		(dnp no)
		(property "Reference" "R217"
			(at 153.67 91.44 0)
			(effects
				(font
					(size 1.27 1.27)
				)
			)
		)
		(property "Value" "R_0R_0402"
			(at 156.21 96.52 0)
			(effects
				(font
					(size 1.27 1.27)
				)
				(justify left bottom)
				(hide yes)
			)
		)
		(property "Footprint" "antmicro-footprints:R_0402_1005Metric"
			(at 161.29 87.63 0)
			(effects
				(font
					(size 1.524 1.524)
				)
				(justify left bottom)
				(hide yes)
			)
		)
		(property "Datasheet" "https://industrial.panasonic.com/cdbs/www-data/pdf/RDA0000/AOA0000C301.pdf"
			(at 156.21 92.71 0)
			(effects
				(font
					(size 1.27 1.27)
				)
				(justify left bottom)
				(hide yes)
			)
		)
		(property "Description" ""
			(at 156.21 92.71 0)
			(effects
				(font
					(size 1.27 1.27)
				)
				(hide yes)
			)
		)
		(property "Manufacturer" "Panasonic"
			(at 161.29 82.55 0)
			(effects
				(font
					(size 1.524 1.524)
				)
				(justify left bottom)
				(hide yes)
			)
		)
		(property "MPN" "ERJ2GE0R00X"
			(at 161.29 85.09 0)
			(effects
				(font
					(size 1.524 1.524)
				)
				(justify left bottom)
				(hide yes)
			)
		)
		(property "Val" "0R"
			(at 162.56 91.44 0)
			(effects
				(font
					(size 1.27 1.27)
				)
			)
		)
		(property "License" "Apache-2.0"
			(at 176.53 118.11 0)
			(effects
				(font
					(size 1.27 1.27)
					(thickness 0.15)
				)
				(justify left bottom)
				(hide yes)
			)
		)
		(property "Author" "Antmicro"
			(at 176.53 120.65 0)
			(effects
				(font
					(size 1.27 1.27)
					(thickness 0.15)
				)
				(justify left bottom)
				(hide yes)
			)
		)
		(property "Tolerance" "~"
			(at 176.53 102.87 0)
			(effects
				(font
					(size 1.27 1.27)
				)
				(justify left bottom)
				(hide yes)
			)
		)
		(property "Current" "1A"
			(at 158.75 90.805 0)
			(effects
				(font
					(size 1.27 1.27)
					(thickness 0.15)
				)
				(hide yes)
			)
		)
		(pin "1"
		)
		(pin "2"
		)
		(instances
			(project "cm4-baseboard"
				(path ""
					(reference "R217")
					(unit 1)
				)
			)
		)
	)
	(symbol
		(lib_id "antmicroResistors0402:R_100k_0402")
		(at 35.56 257.81 90)
		(unit 1)
		(exclude_from_sim no)
		(in_bom yes)
		(on_board yes)
		(dnp no)
		(fields_autoplaced yes)
		(property "Reference" "R204"
			(at 33.02 254 90)
			(effects
				(font
					(size 1.27 1.27)
					(thickness 0.15)
				)
				(justify left)
			)
		)
		(property "Value" "R_100k_0402"
			(at 48.26 237.49 0)
			(effects
				(font
					(size 1.27 1.27)
					(thickness 0.15)
				)
				(justify left bottom)
				(hide yes)
			)
		)
		(property "Footprint" "antmicro-footprints:R_0402_1005Metric"
			(at 50.8 237.49 0)
			(effects
				(font
					(size 1.27 1.27)
					(thickness 0.15)
				)
				(justify left bottom)
				(hide yes)
			)
		)
		(property "Datasheet" "https://www.bourns.com/docs/product-datasheets/cr.pdf"
			(at 53.34 237.49 0)
			(effects
				(font
					(size 1.27 1.27)
					(thickness 0.15)
				)
				(justify left bottom)
				(hide yes)
			)
		)
		(property "Description" ""
			(at 35.56 257.81 0)
			(effects
				(font
					(size 1.27 1.27)
				)
				(hide yes)
			)
		)
		(property "MPN" "CR0402-FX-1003GLF"
			(at 55.88 237.49 0)
			(effects
				(font
					(size 1.27 1.27)
					(thickness 0.15)
				)
				(justify left bottom)
				(hide yes)
			)
		)
		(property "Manufacturer" "Bourns"
			(at 58.42 237.49 0)
			(effects
				(font
					(size 1.27 1.27)
					(thickness 0.15)
				)
				(justify left bottom)
				(hide yes)
			)
		)
		(property "License" "Apache-2.0"
			(at 60.96 237.49 0)
			(effects
				(font
					(size 1.27 1.27)
					(thickness 0.15)
				)
				(justify left bottom)
				(hide yes)
			)
		)
		(property "Author" "Antmicro"
			(at 63.5 237.49 0)
			(effects
				(font
					(size 1.27 1.27)
					(thickness 0.15)
				)
				(justify left bottom)
				(hide yes)
			)
		)
		(property "Val" "100k"
			(at 33.02 256.54 90)
			(effects
				(font
					(size 1.27 1.27)
					(thickness 0.15)
				)
				(justify left)
			)
		)
		(property "Tolerance" "1%"
			(at 45.72 237.49 0)
			(effects
				(font
					(size 1.27 1.27)
				)
				(justify left bottom)
				(hide yes)
			)
		)
		(pin "1"
		)
		(pin "2"
		)
		(instances
			(project "cm4-baseboard"
				(path ""
					(reference "R204")
					(unit 1)
				)
			)
		)
	)
	(symbol
		(lib_id "antmicropower:+3V3")
		(at 275.59 33.02 0)
		(unit 1)
		(exclude_from_sim no)
		(in_bom yes)
		(on_board yes)
		(dnp no)
		(fields_autoplaced yes)
		(property "Reference" "#PWR0251"
			(at 290.83 33.02 0)
			(effects
				(font
					(size 1.27 1.27)
					(thickness 0.15)
				)
				(justify left bottom)
				(hide yes)
			)
		)
		(property "Value" "+3V3"
			(at 275.59 27.94 0)
			(effects
				(font
					(size 1.27 1.27)
					(thickness 0.15)
				)
			)
		)
		(property "Footprint" ""
			(at 290.83 40.64 0)
			(effects
				(font
					(size 1.27 1.27)
					(thickness 0.15)
				)
				(justify left bottom)
				(hide yes)
			)
		)
		(property "Datasheet" ""
			(at 290.83 43.18 0)
			(effects
				(font
					(size 1.27 1.27)
					(thickness 0.15)
				)
				(justify left bottom)
				(hide yes)
			)
		)
		(property "Description" ""
			(at 275.59 33.02 0)
			(effects
				(font
					(size 1.27 1.27)
				)
				(hide yes)
			)
		)
		(property "Author" "Antmicro"
			(at 290.83 35.56 0)
			(effects
				(font
					(size 1.27 1.27)
					(thickness 0.15)
				)
				(justify left bottom)
				(hide yes)
			)
		)
		(property "License" "Apache-2.0"
			(at 290.83 38.1 0)
			(effects
				(font
					(size 1.27 1.27)
					(thickness 0.15)
				)
				(justify left bottom)
				(hide yes)
			)
		)
		(pin "1"
		)
		(instances
			(project "cm4-baseboard"
				(path ""
					(reference "#PWR0251")
					(unit 1)
				)
			)
		)
	)
	(symbol
		(lib_id "antmicroCapacitors0402:C_100n_0402")
		(at 266.7 127 90)
		(unit 1)
		(exclude_from_sim no)
		(in_bom yes)
		(on_board yes)
		(dnp no)
		(property "Reference" "C207"
			(at 267.97 121.92 90)
			(effects
				(font
					(size 1.27 1.27)
					(thickness 0.15)
				)
				(justify right)
			)
		)
		(property "Value" "C_100n_0402"
			(at 276.86 106.68 0)
			(effects
				(font
					(size 1.27 1.27)
					(thickness 0.15)
				)
				(justify left bottom)
				(hide yes)
			)
		)
		(property "Footprint" "antmicro-footprints:C_0402_1005Metric"
			(at 279.4 106.68 0)
			(effects
				(font
					(size 1.27 1.27)
					(thickness 0.15)
				)
				(justify left bottom)
				(hide yes)
			)
		)
		(property "Datasheet" "https://www.murata.com/products/productdetail?partno=GRM155R61H104KE14%23"
			(at 281.94 106.68 0)
			(effects
				(font
					(size 1.27 1.27)
					(thickness 0.15)
				)
				(justify left bottom)
				(hide yes)
			)
		)
		(property "Description" ""
			(at 266.7 127 0)
			(effects
				(font
					(size 1.27 1.27)
				)
				(hide yes)
			)
		)
		(property "MPN" "GRM155R61H104KE14D"
			(at 284.48 106.68 0)
			(effects
				(font
					(size 1.27 1.27)
					(thickness 0.15)
				)
				(justify left bottom)
				(hide yes)
			)
		)
		(property "Manufacturer" "Murata"
			(at 287.02 106.68 0)
			(effects
				(font
					(size 1.27 1.27)
					(thickness 0.15)
				)
				(justify left bottom)
				(hide yes)
			)
		)
		(property "License" "Apache-2.0"
			(at 289.56 106.68 0)
			(effects
				(font
					(size 1.27 1.27)
					(thickness 0.15)
				)
				(justify left bottom)
				(hide yes)
			)
		)
		(property "Author" "Antmicro"
			(at 292.1 106.68 0)
			(effects
				(font
					(size 1.27 1.27)
					(thickness 0.15)
				)
				(justify left bottom)
				(hide yes)
			)
		)
		(property "Val" "100n"
			(at 267.97 127 90)
			(effects
				(font
					(size 1.27 1.27)
					(thickness 0.15)
				)
				(justify right)
			)
		)
		(property "Voltage" "50V"
			(at 294.64 106.68 0)
			(effects
				(font
					(size 1.27 1.27)
				)
				(justify left bottom)
				(hide yes)
			)
		)
		(property "Dielectric" "X5R"
			(at 297.18 106.68 0)
			(effects
				(font
					(size 1.27 1.27)
				)
				(justify left bottom)
				(hide yes)
			)
		)
		(pin "1"
		)
		(pin "2"
		)
		(instances
			(project "cm4-baseboard"
				(path ""
					(reference "C207")
					(unit 1)
				)
			)
		)
	)
	(symbol
		(lib_id "antmicroResistors0402:R_10k_0402")
		(at 240.03 74.93 270)
		(mirror x)
		(unit 1)
		(exclude_from_sim no)
		(in_bom yes)
		(on_board yes)
		(dnp no)
		(property "Reference" "R231"
			(at 238.76 71.12 90)
			(effects
				(font
					(size 1.27 1.27)
					(thickness 0.15)
				)
				(justify right)
			)
		)
		(property "Value" "R_10k_0402"
			(at 227.33 54.61 0)
			(effects
				(font
					(size 1.27 1.27)
					(thickness 0.15)
				)
				(justify left bottom)
				(hide yes)
			)
		)
		(property "Footprint" "antmicro-footprints:R_0402_1005Metric"
			(at 224.79 54.61 0)
			(effects
				(font
					(size 1.27 1.27)
					(thickness 0.15)
				)
				(justify left bottom)
				(hide yes)
			)
		)
		(property "Datasheet" "https://www.bourns.com/docs/product-datasheets/cr.pdf"
			(at 222.25 54.61 0)
			(effects
				(font
					(size 1.27 1.27)
					(thickness 0.15)
				)
				(justify left bottom)
				(hide yes)
			)
		)
		(property "Description" ""
			(at 240.03 74.93 0)
			(effects
				(font
					(size 1.27 1.27)
				)
				(hide yes)
			)
		)
		(property "MPN" "CR0402-FX-1002GLF"
			(at 219.71 54.61 0)
			(effects
				(font
					(size 1.27 1.27)
					(thickness 0.15)
				)
				(justify left bottom)
				(hide yes)
			)
		)
		(property "Manufacturer" "Bourns"
			(at 217.17 54.61 0)
			(effects
				(font
					(size 1.27 1.27)
					(thickness 0.15)
				)
				(justify left bottom)
				(hide yes)
			)
		)
		(property "License" "Apache-2.0"
			(at 214.63 54.61 0)
			(effects
				(font
					(size 1.27 1.27)
					(thickness 0.15)
				)
				(justify left bottom)
				(hide yes)
			)
		)
		(property "Author" "Antmicro"
			(at 212.09 54.61 0)
			(effects
				(font
					(size 1.27 1.27)
					(thickness 0.15)
				)
				(justify left bottom)
				(hide yes)
			)
		)
		(property "Val" "10k"
			(at 238.76 73.66 90)
			(effects
				(font
					(size 1.27 1.27)
					(thickness 0.15)
				)
				(justify right)
			)
		)
		(property "Tolerance" "1%"
			(at 229.87 54.61 0)
			(effects
				(font
					(size 1.27 1.27)
				)
				(justify left bottom)
				(hide yes)
			)
		)
		(pin "1"
		)
		(pin "2"
		)
		(instances
			(project "cm4-baseboard"
				(path ""
					(reference "R231")
					(unit 1)
				)
			)
		)
	)
	(symbol
		(lib_id "antmicroResistors0402:R_100k_0402")
		(at 218.44 193.04 270)
		(mirror x)
		(unit 1)
		(exclude_from_sim no)
		(in_bom yes)
		(on_board yes)
		(dnp no)
		(property "Reference" "R1"
			(at 217.17 189.23 90)
			(effects
				(font
					(size 1.27 1.27)
				)
				(justify right)
			)
		)
		(property "Value" "R_100k_0402"
			(at 214.63 193.04 0)
			(effects
				(font
					(size 1.27 1.27)
				)
				(justify left bottom)
				(hide yes)
			)
		)
		(property "Footprint" "antmicro-footprints:R_0402_1005Metric"
			(at 223.52 187.96 0)
			(effects
				(font
					(size 1.524 1.524)
				)
				(justify left bottom)
				(hide yes)
			)
		)
		(property "Datasheet" "https://www.bourns.com/docs/product-datasheets/cr.pdf"
			(at 218.44 193.04 0)
			(effects
				(font
					(size 1.27 1.27)
				)
				(justify left bottom)
				(hide yes)
			)
		)
		(property "Description" ""
			(at 218.44 193.04 0)
			(effects
				(font
					(size 1.27 1.27)
				)
				(hide yes)
			)
		)
		(property "Manufacturer" "Bourns"
			(at 228.6 187.96 0)
			(effects
				(font
					(size 1.524 1.524)
				)
				(justify left bottom)
				(hide yes)
			)
		)
		(property "MPN" "CR0402-FX-1003GLF"
			(at 226.06 187.96 0)
			(effects
				(font
					(size 1.524 1.524)
				)
				(justify left bottom)
				(hide yes)
			)
		)
		(property "Val" "100k"
			(at 217.17 191.77 90)
			(effects
				(font
					(size 1.27 1.27)
				)
				(justify right)
			)
		)
		(property "License" "Apache-2.0"
			(at 193.04 172.72 0)
			(effects
				(font
					(size 1.27 1.27)
					(thickness 0.15)
				)
				(justify left bottom)
				(hide yes)
			)
		)
		(property "Author" "Antmicro"
			(at 190.5 172.72 0)
			(effects
				(font
					(size 1.27 1.27)
					(thickness 0.15)
				)
				(justify left bottom)
				(hide yes)
			)
		)
		(property "Tolerance" "1%"
			(at 208.28 172.72 0)
			(effects
				(font
					(size 1.27 1.27)
				)
				(justify left bottom)
				(hide yes)
			)
		)
		(pin "1"
		)
		(pin "2"
		)
		(instances
			(project "cm4-baseboard"
				(path ""
					(reference "R1")
					(unit 1)
				)
			)
		)
	)
	(symbol
		(lib_id "antmicroPushbuttonSwitches:SW_KMR211NGLFS_SMD")
		(at 132.08 224.79 90)
		(mirror x)
		(unit 1)
		(exclude_from_sim no)
		(in_bom yes)
		(on_board yes)
		(dnp no)
		(property "Reference" "S202"
			(at 129.54 232.41 90)
			(effects
				(font
					(size 1.27 1.27)
				)
				(justify left)
			)
		)
		(property "Value" "SW_KMR211NGLFS_SMD"
			(at 144.78 231.14 90)
			(effects
				(font
					(size 1.27 1.27)
				)
				(justify left)
				(hide yes)
			)
		)
		(property "Footprint" "antmicro-footprints:SW_KMR211NGLFS_SMD"
			(at 127 229.87 0)
			(effects
				(font
					(size 1.27 1.27)
				)
				(justify left bottom)
				(hide yes)
			)
		)
		(property "Datasheet" "http://www.farnell.com/datasheets/2631211.pdf"
			(at 124.46 229.87 0)
			(effects
				(font
					(size 1.524 1.524)
				)
				(justify left bottom)
				(hide yes)
			)
		)
		(property "Description" ""
			(at 132.08 224.79 0)
			(effects
				(font
					(size 1.27 1.27)
				)
				(hide yes)
			)
		)
		(property "MPN" "KMR211NGLFS"
			(at 129.54 236.22 90)
			(effects
				(font
					(size 1.27 1.27)
				)
				(justify left bottom)
			)
		)
		(property "Manufacturer" "C&K"
			(at 120.0912 229.87 0)
			(effects
				(font
					(size 1.524 1.524)
				)
				(justify left bottom)
				(hide yes)
			)
		)
		(property "Author" "Antmicro"
			(at 149.86 250.19 0)
			(effects
				(font
					(size 1.27 1.27)
					(thickness 0.15)
				)
				(justify left bottom)
				(hide yes)
			)
		)
		(property "License" "Apache-2.0"
			(at 152.4 250.19 0)
			(effects
				(font
					(size 1.27 1.27)
					(thickness 0.15)
				)
				(justify left bottom)
				(hide yes)
			)
		)
		(pin "1"
		)
		(pin "2"
		)
		(pin "3"
		)
		(pin "4"
		)
		(instances
			(project "cm4-baseboard"
				(path ""
					(reference "S202")
					(unit 1)
				)
			)
		)
	)
	(symbol
		(lib_id "antmicroTransistorsFETsMOSFETsSingle:PJE138K")
		(at 133.35 269.24 0)
		(unit 1)
		(exclude_from_sim no)
		(in_bom yes)
		(on_board yes)
		(dnp no)
		(fields_autoplaced yes)
		(property "Reference" "Q207"
			(at 144.78 265.4299 0)
			(effects
				(font
					(size 1.27 1.27)
					(thickness 0.15)
				)
				(justify left)
			)
		)
		(property "Value" "PJE138K"
			(at 144.78 267.9699 0)
			(effects
				(font
					(size 1.27 1.27)
					(thickness 0.15)
				)
				(justify left)
			)
		)
		(property "Footprint" "antmicro-footprints:SOT-523"
			(at 156.21 280.67 0)
			(effects
				(font
					(size 1.27 1.27)
					(thickness 0.15)
				)
				(justify left bottom)
				(hide yes)
			)
		)
		(property "Datasheet" "https://www.mouser.com/datasheet/2/1057/PJE138K-1876698.pdf"
			(at 156.21 283.21 0)
			(effects
				(font
					(size 1.27 1.27)
					(thickness 0.15)
				)
				(justify left bottom)
				(hide yes)
			)
		)
		(property "Description" ""
			(at 133.35 269.24 0)
			(effects
				(font
					(size 1.27 1.27)
				)
				(hide yes)
			)
		)
		(property "MPN" "PJE138K_R1_00001"
			(at 156.21 285.75 0)
			(effects
				(font
					(size 1.27 1.27)
					(thickness 0.15)
				)
				(justify left bottom)
				(hide yes)
			)
		)
		(property "Manufacturer" "PANJIT"
			(at 156.21 288.29 0)
			(effects
				(font
					(size 1.27 1.27)
					(thickness 0.15)
				)
				(justify left bottom)
				(hide yes)
			)
		)
		(property "Author" "Antmicro"
			(at 156.21 290.83 0)
			(effects
				(font
					(size 1.27 1.27)
					(thickness 0.15)
				)
				(justify left bottom)
				(hide yes)
			)
		)
		(property "License" "Apache-2.0"
			(at 156.21 293.37 0)
			(effects
				(font
					(size 1.27 1.27)
					(thickness 0.15)
				)
				(justify left bottom)
				(hide yes)
			)
		)
		(pin "1"
		)
		(pin "2"
		)
		(pin "3"
		)
		(instances
			(project "cm4-baseboard"
				(path ""
					(reference "Q207")
					(unit 1)
				)
			)
		)
	)
	(symbol
		(lib_id "antmicropower:+1V8")
		(at 168.91 213.36 0)
		(unit 1)
		(exclude_from_sim no)
		(in_bom yes)
		(on_board yes)
		(dnp no)
		(property "Reference" "#PWR0223"
			(at 184.15 215.9 0)
			(effects
				(font
					(size 1.27 1.27)
					(thickness 0.15)
				)
				(justify left bottom)
				(hide yes)
			)
		)
		(property "Value" "+1V8"
			(at 171.45 209.55 0)
			(effects
				(font
					(size 1.27 1.27)
					(thickness 0.15)
				)
				(justify right)
			)
		)
		(property "Footprint" ""
			(at 184.15 220.98 0)
			(effects
				(font
					(size 1.27 1.27)
					(thickness 0.15)
				)
				(justify left bottom)
				(hide yes)
			)
		)
		(property "Datasheet" ""
			(at 184.15 223.52 0)
			(effects
				(font
					(size 1.27 1.27)
					(thickness 0.15)
				)
				(justify left bottom)
				(hide yes)
			)
		)
		(property "Description" ""
			(at 168.91 213.36 0)
			(effects
				(font
					(size 1.27 1.27)
				)
				(hide yes)
			)
		)
		(property "Author" "Antmicro"
			(at 184.15 218.44 0)
			(effects
				(font
					(size 1.27 1.27)
					(thickness 0.15)
				)
				(justify left bottom)
				(hide yes)
			)
		)
		(property "License" "Apache-2.0"
			(at 184.15 220.98 0)
			(effects
				(font
					(size 1.27 1.27)
					(thickness 0.15)
				)
				(justify left bottom)
				(hide yes)
			)
		)
		(pin "1"
		)
		(instances
			(project "cm4-baseboard"
				(path ""
					(reference "#PWR0223")
					(unit 1)
				)
			)
		)
	)
	(symbol
		(lib_id "antmicroResistors0402:R_100k_0402")
		(at 130.81 271.78 270)
		(unit 1)
		(exclude_from_sim no)
		(in_bom yes)
		(on_board yes)
		(dnp no)
		(property "Reference" "R214"
			(at 132.08 273.05 90)
			(effects
				(font
					(size 1.27 1.27)
					(thickness 0.15)
				)
				(justify left)
			)
		)
		(property "Value" "R_100k_0402"
			(at 118.11 292.1 0)
			(effects
				(font
					(size 1.27 1.27)
					(thickness 0.15)
				)
				(justify left bottom)
				(hide yes)
			)
		)
		(property "Footprint" "antmicro-footprints:R_0402_1005Metric"
			(at 115.57 292.1 0)
			(effects
				(font
					(size 1.27 1.27)
					(thickness 0.15)
				)
				(justify left bottom)
				(hide yes)
			)
		)
		(property "Datasheet" "https://www.bourns.com/docs/product-datasheets/cr.pdf"
			(at 113.03 292.1 0)
			(effects
				(font
					(size 1.27 1.27)
					(thickness 0.15)
				)
				(justify left bottom)
				(hide yes)
			)
		)
		(property "Description" ""
			(at 130.81 271.78 0)
			(effects
				(font
					(size 1.27 1.27)
				)
				(hide yes)
			)
		)
		(property "Manufacturer" "Bourns"
			(at 107.95 292.1 0)
			(effects
				(font
					(size 1.27 1.27)
					(thickness 0.15)
				)
				(justify left bottom)
				(hide yes)
			)
		)
		(property "MPN" "CR0402-FX-1003GLF"
			(at 110.49 292.1 0)
			(effects
				(font
					(size 1.27 1.27)
					(thickness 0.15)
				)
				(justify left bottom)
				(hide yes)
			)
		)
		(property "Val" "100k"
			(at 132.08 275.59 90)
			(effects
				(font
					(size 1.27 1.27)
					(thickness 0.15)
				)
				(justify left)
			)
		)
		(property "License" "Apache-2.0"
			(at 105.41 292.1 0)
			(effects
				(font
					(size 1.27 1.27)
					(thickness 0.15)
				)
				(justify left bottom)
				(hide yes)
			)
		)
		(property "Author" "Antmicro"
			(at 102.87 292.1 0)
			(effects
				(font
					(size 1.27 1.27)
					(thickness 0.15)
				)
				(justify left bottom)
				(hide yes)
			)
		)
		(property "Tolerance" "1%"
			(at 120.65 292.1 0)
			(effects
				(font
					(size 1.27 1.27)
				)
				(justify left bottom)
				(hide yes)
			)
		)
		(pin "1"
		)
		(pin "2"
		)
		(instances
			(project "cm4-baseboard"
				(path ""
					(reference "R214")
					(unit 1)
				)
			)
		)
	)
	(symbol
		(lib_id "antmicropower:GND")
		(at 266.7 128.27 0)
		(unit 1)
		(exclude_from_sim no)
		(in_bom yes)
		(on_board yes)
		(dnp no)
		(property "Reference" "#PWR0254"
			(at 275.59 130.81 0)
			(effects
				(font
					(size 1.27 1.27)
					(thickness 0.15)
				)
				(justify left bottom)
				(hide yes)
			)
		)
		(property "Value" "GND"
			(at 266.7 132.715 0)
			(effects
				(font
					(size 1.27 1.27)
					(thickness 0.15)
				)
			)
		)
		(property "Footprint" ""
			(at 275.59 135.89 0)
			(effects
				(font
					(size 1.27 1.27)
					(thickness 0.15)
				)
				(justify left bottom)
				(hide yes)
			)
		)
		(property "Datasheet" ""
			(at 275.59 140.97 0)
			(effects
				(font
					(size 1.27 1.27)
					(thickness 0.15)
				)
				(justify left bottom)
				(hide yes)
			)
		)
		(property "Description" ""
			(at 266.7 128.27 0)
			(effects
				(font
					(size 1.27 1.27)
				)
				(hide yes)
			)
		)
		(property "Author" "Antmicro"
			(at 275.59 135.89 0)
			(effects
				(font
					(size 1.27 1.27)
					(thickness 0.15)
				)
				(justify left bottom)
				(hide yes)
			)
		)
		(property "License" "Apache-2.0"
			(at 275.59 138.43 0)
			(effects
				(font
					(size 1.27 1.27)
					(thickness 0.15)
				)
				(justify left bottom)
				(hide yes)
			)
		)
		(pin "1"
		)
		(instances
			(project "cm4-baseboard"
				(path ""
					(reference "#PWR0254")
					(unit 1)
				)
			)
		)
	)
	(symbol
		(lib_id "antmicroCapacitors0402:C_10u_0402")
		(at 287.02 93.98 90)
		(unit 1)
		(exclude_from_sim no)
		(in_bom yes)
		(on_board yes)
		(dnp no)
		(fields_autoplaced yes)
		(property "Reference" "C209"
			(at 284.48 90.1635 90)
			(effects
				(font
					(size 1.27 1.27)
					(thickness 0.15)
				)
				(justify left)
			)
		)
		(property "Value" "C_10u_0402"
			(at 297.18 73.66 0)
			(effects
				(font
					(size 1.27 1.27)
					(thickness 0.15)
				)
				(justify left bottom)
				(hide yes)
			)
		)
		(property "Footprint" "antmicro-footprints:C_0402_1005Metric"
			(at 299.72 73.66 0)
			(effects
				(font
					(size 1.27 1.27)
					(thickness 0.15)
				)
				(justify left bottom)
				(hide yes)
			)
		)
		(property "Datasheet" "https://www.yageo.com/en/Chart/Download/pdf/CC0402MRX5R5BB106"
			(at 302.26 73.66 0)
			(effects
				(font
					(size 1.27 1.27)
					(thickness 0.15)
				)
				(justify left bottom)
				(hide yes)
			)
		)
		(property "Description" ""
			(at 287.02 93.98 0)
			(effects
				(font
					(size 1.27 1.27)
				)
				(hide yes)
			)
		)
		(property "MPN" "CC0402MRX5R5BB106"
			(at 304.8 73.66 0)
			(effects
				(font
					(size 1.27 1.27)
					(thickness 0.15)
				)
				(justify left bottom)
				(hide yes)
			)
		)
		(property "Manufacturer" "YAGEO"
			(at 307.34 73.66 0)
			(effects
				(font
					(size 1.27 1.27)
					(thickness 0.15)
				)
				(justify left bottom)
				(hide yes)
			)
		)
		(property "License" "Apache-2.0"
			(at 309.88 73.66 0)
			(effects
				(font
					(size 1.27 1.27)
					(thickness 0.15)
				)
				(justify left bottom)
				(hide yes)
			)
		)
		(property "Author" "Antmicro"
			(at 312.42 73.66 0)
			(effects
				(font
					(size 1.27 1.27)
					(thickness 0.15)
				)
				(justify left bottom)
				(hide yes)
			)
		)
		(property "Val" "10u"
			(at 284.48 92.7035 90)
			(effects
				(font
					(size 1.27 1.27)
					(thickness 0.15)
				)
				(justify left)
			)
		)
		(property "Voltage" ""
			(at 314.96 73.66 0)
			(effects
				(font
					(size 1.27 1.27)
				)
				(justify left bottom)
				(hide yes)
			)
		)
		(property "Dielectric" ""
			(at 317.5 73.66 0)
			(effects
				(font
					(size 1.27 1.27)
				)
				(justify left bottom)
				(hide yes)
			)
		)
		(pin "1"
		)
		(pin "2"
		)
		(instances
			(project "cm4-baseboard"
				(path ""
					(reference "C209")
					(unit 1)
				)
			)
		)
	)
	(symbol
		(lib_id "antmicroTestPoints:TP_0.75mm_SMD")
		(at 43.18 148.59 180)
		(unit 1)
		(exclude_from_sim no)
		(in_bom no)
		(on_board yes)
		(dnp no)
		(property "Reference" "TP201"
			(at 35.56 148.59 0)
			(effects
				(font
					(size 1.27 1.27)
					(thickness 0.15)
				)
			)
		)
		(property "Value" "TP_0.75mm_SMD"
			(at 27.94 140.97 0)
			(effects
				(font
					(size 1.27 1.27)
					(thickness 0.15)
				)
				(justify left bottom)
				(hide yes)
			)
		)
		(property "Footprint" "antmicro-footprints:TP_SMD_0.75mm"
			(at 32.385 142.24 0)
			(effects
				(font
					(size 1.27 1.27)
					(thickness 0.15)
				)
				(justify left bottom)
				(hide yes)
			)
		)
		(property "Datasheet" ""
			(at 25.4 135.89 0)
			(effects
				(font
					(size 1.27 1.27)
					(thickness 0.15)
				)
				(justify left bottom)
				(hide yes)
			)
		)
		(property "Description" ""
			(at 43.18 148.59 0)
			(effects
				(font
					(size 1.27 1.27)
				)
				(hide yes)
			)
		)
		(property "Author" "Antmicro"
			(at 32.385 139.7 0)
			(effects
				(font
					(size 1.27 1.27)
					(thickness 0.15)
				)
				(justify left bottom)
				(hide yes)
			)
		)
		(property "License" "Apache-2.0"
			(at 32.385 137.16 0)
			(effects
				(font
					(size 1.27 1.27)
					(thickness 0.15)
				)
				(justify left bottom)
				(hide yes)
			)
		)
		(property "MPN" ""
			(at 32.385 137.16 0)
			(effects
				(font
					(size 1.27 1.27)
					(thickness 0.15)
				)
				(justify left bottom)
				(hide yes)
			)
		)
		(property "Manufacturer" ""
			(at 32.385 142.24 0)
			(effects
				(font
					(size 1.27 1.27)
					(thickness 0.15)
				)
				(justify left bottom)
				(hide yes)
			)
		)
		(pin "1"
		)
		(instances
			(project "cm4-baseboard"
				(path ""
					(reference "TP201")
					(unit 1)
				)
			)
		)
	)
	(symbol
		(lib_id "antmicroResistors0402:R_0R_0402")
		(at 196.85 105.41 0)
		(unit 1)
		(exclude_from_sim no)
		(in_bom yes)
		(on_board yes)
		(dnp no)
		(property "Reference" "R225"
			(at 194.31 104.14 0)
			(effects
				(font
					(size 1.27 1.27)
				)
			)
		)
		(property "Value" "R_0R_0402"
			(at 196.85 109.22 0)
			(effects
				(font
					(size 1.27 1.27)
				)
				(justify left bottom)
				(hide yes)
			)
		)
		(property "Footprint" "antmicro-footprints:R_0402_1005Metric"
			(at 201.93 100.33 0)
			(effects
				(font
					(size 1.524 1.524)
				)
				(justify left bottom)
				(hide yes)
			)
		)
		(property "Datasheet" "https://industrial.panasonic.com/cdbs/www-data/pdf/RDA0000/AOA0000C301.pdf"
			(at 196.85 105.41 0)
			(effects
				(font
					(size 1.27 1.27)
				)
				(justify left bottom)
				(hide yes)
			)
		)
		(property "Description" ""
			(at 196.85 105.41 0)
			(effects
				(font
					(size 1.27 1.27)
				)
				(hide yes)
			)
		)
		(property "Manufacturer" "Panasonic"
			(at 201.93 95.25 0)
			(effects
				(font
					(size 1.524 1.524)
				)
				(justify left bottom)
				(hide yes)
			)
		)
		(property "MPN" "ERJ2GE0R00X"
			(at 201.93 97.79 0)
			(effects
				(font
					(size 1.524 1.524)
				)
				(justify left bottom)
				(hide yes)
			)
		)
		(property "Val" "0R"
			(at 203.2 104.14 0)
			(effects
				(font
					(size 1.27 1.27)
				)
			)
		)
		(property "License" "Apache-2.0"
			(at 217.17 130.81 0)
			(effects
				(font
					(size 1.27 1.27)
					(thickness 0.15)
				)
				(justify left bottom)
				(hide yes)
			)
		)
		(property "Author" "Antmicro"
			(at 217.17 133.35 0)
			(effects
				(font
					(size 1.27 1.27)
					(thickness 0.15)
				)
				(justify left bottom)
				(hide yes)
			)
		)
		(property "Tolerance" "~"
			(at 217.17 115.57 0)
			(effects
				(font
					(size 1.27 1.27)
				)
				(justify left bottom)
				(hide yes)
			)
		)
		(property "Current" "1A"
			(at 199.39 103.505 0)
			(effects
				(font
					(size 1.27 1.27)
					(thickness 0.15)
				)
				(hide yes)
			)
		)
		(pin "1"
		)
		(pin "2"
		)
		(instances
			(project "cm4-baseboard"
				(path ""
					(reference "R225")
					(unit 1)
				)
			)
		)
	)
	(symbol
		(lib_id "antmicroTransistorsFETsMOSFETsSingle:PJE138K")
		(at 38.1 251.46 0)
		(unit 1)
		(exclude_from_sim no)
		(in_bom yes)
		(on_board yes)
		(dnp no)
		(fields_autoplaced yes)
		(property "Reference" "Q201"
			(at 49.53 247.6499 0)
			(effects
				(font
					(size 1.27 1.27)
					(thickness 0.15)
				)
				(justify left)
			)
		)
		(property "Value" "PJE138K"
			(at 49.53 250.1899 0)
			(effects
				(font
					(size 1.27 1.27)
					(thickness 0.15)
				)
				(justify left)
			)
		)
		(property "Footprint" "antmicro-footprints:SOT-523"
			(at 60.96 262.89 0)
			(effects
				(font
					(size 1.27 1.27)
					(thickness 0.15)
				)
				(justify left bottom)
				(hide yes)
			)
		)
		(property "Datasheet" "https://www.mouser.com/datasheet/2/1057/PJE138K-1876698.pdf"
			(at 60.96 265.43 0)
			(effects
				(font
					(size 1.27 1.27)
					(thickness 0.15)
				)
				(justify left bottom)
				(hide yes)
			)
		)
		(property "Description" ""
			(at 38.1 251.46 0)
			(effects
				(font
					(size 1.27 1.27)
				)
				(hide yes)
			)
		)
		(property "MPN" "PJE138K_R1_00001"
			(at 60.96 267.97 0)
			(effects
				(font
					(size 1.27 1.27)
					(thickness 0.15)
				)
				(justify left bottom)
				(hide yes)
			)
		)
		(property "Manufacturer" "PANJIT"
			(at 60.96 270.51 0)
			(effects
				(font
					(size 1.27 1.27)
					(thickness 0.15)
				)
				(justify left bottom)
				(hide yes)
			)
		)
		(property "Author" "Antmicro"
			(at 60.96 273.05 0)
			(effects
				(font
					(size 1.27 1.27)
					(thickness 0.15)
				)
				(justify left bottom)
				(hide yes)
			)
		)
		(property "License" "Apache-2.0"
			(at 60.96 275.59 0)
			(effects
				(font
					(size 1.27 1.27)
					(thickness 0.15)
				)
				(justify left bottom)
				(hide yes)
			)
		)
		(pin "1"
		)
		(pin "2"
		)
		(pin "3"
		)
		(instances
			(project "cm4-baseboard"
				(path ""
					(reference "Q201")
					(unit 1)
				)
			)
		)
	)
	(symbol
		(lib_id "antmicropower:GND")
		(at 123.19 246.38 0)
		(unit 1)
		(exclude_from_sim no)
		(in_bom yes)
		(on_board yes)
		(dnp no)
		(property "Reference" "#PWR0215"
			(at 123.19 252.73 0)
			(effects
				(font
					(size 1.27 1.27)
				)
				(justify left bottom)
				(hide yes)
			)
		)
		(property "Value" "GND"
			(at 123.19 250.19 0)
			(effects
				(font
					(size 1.27 1.27)
				)
			)
		)
		(property "Footprint" ""
			(at 132.08 254 0)
			(effects
				(font
					(size 1.27 1.27)
					(thickness 0.15)
				)
				(justify left bottom)
				(hide yes)
			)
		)
		(property "Datasheet" ""
			(at 132.08 259.08 0)
			(effects
				(font
					(size 1.27 1.27)
					(thickness 0.15)
				)
				(justify left bottom)
				(hide yes)
			)
		)
		(property "Description" ""
			(at 123.19 246.38 0)
			(effects
				(font
					(size 1.27 1.27)
				)
				(hide yes)
			)
		)
		(property "Author" "Antmicro"
			(at 132.08 254 0)
			(effects
				(font
					(size 1.27 1.27)
					(thickness 0.15)
				)
				(justify left bottom)
				(hide yes)
			)
		)
		(property "License" "Apache-2.0"
			(at 132.08 256.54 0)
			(effects
				(font
					(size 1.27 1.27)
					(thickness 0.15)
				)
				(justify left bottom)
				(hide yes)
			)
		)
		(pin "1"
		)
		(instances
			(project "cm4-baseboard"
				(path ""
					(reference "#PWR0215")
					(unit 1)
				)
			)
		)
	)
	(symbol
		(lib_id "antmicroTestPoints:TP_0.75mm_SMD")
		(at 187.96 215.9 0)
		(mirror y)
		(unit 1)
		(exclude_from_sim no)
		(in_bom no)
		(on_board yes)
		(dnp no)
		(property "Reference" "TP213"
			(at 187.96 218.44 0)
			(effects
				(font
					(size 1.27 1.27)
					(thickness 0.15)
				)
				(justify left)
			)
		)
		(property "Value" "TP_0.75mm_SMD"
			(at 172.72 223.52 0)
			(effects
				(font
					(size 1.27 1.27)
					(thickness 0.15)
				)
				(justify left bottom)
				(hide yes)
			)
		)
		(property "Footprint" "antmicro-footprints:TP_SMD_0.75mm"
			(at 177.165 222.25 0)
			(effects
				(font
					(size 1.27 1.27)
					(thickness 0.15)
				)
				(justify left bottom)
				(hide yes)
			)
		)
		(property "Datasheet" ""
			(at 170.18 228.6 0)
			(effects
				(font
					(size 1.27 1.27)
					(thickness 0.15)
				)
				(justify left bottom)
				(hide yes)
			)
		)
		(property "Description" ""
			(at 187.96 215.9 0)
			(effects
				(font
					(size 1.27 1.27)
				)
				(hide yes)
			)
		)
		(property "Author" "Antmicro"
			(at 177.165 224.79 0)
			(effects
				(font
					(size 1.27 1.27)
					(thickness 0.15)
				)
				(justify left bottom)
				(hide yes)
			)
		)
		(property "License" "Apache-2.0"
			(at 177.165 227.33 0)
			(effects
				(font
					(size 1.27 1.27)
					(thickness 0.15)
				)
				(justify left bottom)
				(hide yes)
			)
		)
		(property "MPN" ""
			(at 177.165 227.33 0)
			(effects
				(font
					(size 1.27 1.27)
					(thickness 0.15)
				)
				(justify left bottom)
				(hide yes)
			)
		)
		(property "Manufacturer" ""
			(at 177.165 222.25 0)
			(effects
				(font
					(size 1.27 1.27)
					(thickness 0.15)
				)
				(justify left bottom)
				(hide yes)
			)
		)
		(pin "1"
		)
		(instances
			(project "cm4-baseboard"
				(path ""
					(reference "TP213")
					(unit 1)
				)
			)
		)
	)
	(symbol
		(lib_id "antmicropower:GND")
		(at 340.36 143.51 0)
		(unit 1)
		(exclude_from_sim no)
		(in_bom yes)
		(on_board yes)
		(dnp no)
		(property "Reference" "#PWR0225"
			(at 349.25 146.05 0)
			(effects
				(font
					(size 1.27 1.27)
					(thickness 0.15)
				)
				(justify left bottom)
				(hide yes)
			)
		)
		(property "Value" "GND"
			(at 338.3498 148.59 0)
			(effects
				(font
					(size 1.27 1.27)
					(thickness 0.15)
				)
				(justify left bottom)
			)
		)
		(property "Footprint" ""
			(at 349.25 151.13 0)
			(effects
				(font
					(size 1.27 1.27)
					(thickness 0.15)
				)
				(justify left bottom)
				(hide yes)
			)
		)
		(property "Datasheet" ""
			(at 349.25 156.21 0)
			(effects
				(font
					(size 1.27 1.27)
					(thickness 0.15)
				)
				(justify left bottom)
				(hide yes)
			)
		)
		(property "Description" ""
			(at 340.36 143.51 0)
			(effects
				(font
					(size 1.27 1.27)
				)
				(hide yes)
			)
		)
		(property "Author" "Antmicro"
			(at 349.25 151.13 0)
			(effects
				(font
					(size 1.27 1.27)
					(thickness 0.15)
				)
				(justify left bottom)
				(hide yes)
			)
		)
		(property "License" "Apache-2.0"
			(at 349.25 153.67 0)
			(effects
				(font
					(size 1.27 1.27)
					(thickness 0.15)
				)
				(justify left bottom)
				(hide yes)
			)
		)
		(pin "1"
		)
		(instances
			(project "cm4-baseboard"
				(path ""
					(reference "#PWR0225")
					(unit 1)
				)
			)
		)
	)
	(symbol
		(lib_id "antmicroTransistorsFETsMOSFETsSingle:PJE138K")
		(at 170.18 215.9 0)
		(unit 1)
		(exclude_from_sim no)
		(in_bom yes)
		(on_board yes)
		(dnp no)
		(property "Reference" "Q210"
			(at 171.45 218.44 0)
			(effects
				(font
					(size 1.27 1.27)
					(thickness 0.15)
				)
				(justify left)
			)
		)
		(property "Value" "PJE138K"
			(at 180.34 217.17 90)
			(effects
				(font
					(size 1.27 1.27)
					(thickness 0.15)
				)
				(justify left)
			)
		)
		(property "Footprint" "antmicro-footprints:SOT-523"
			(at 193.04 227.33 0)
			(effects
				(font
					(size 1.27 1.27)
					(thickness 0.15)
				)
				(justify left bottom)
				(hide yes)
			)
		)
		(property "Datasheet" "https://www.mouser.com/datasheet/2/1057/PJE138K-1876698.pdf"
			(at 193.04 229.87 0)
			(effects
				(font
					(size 1.27 1.27)
					(thickness 0.15)
				)
				(justify left bottom)
				(hide yes)
			)
		)
		(property "Description" ""
			(at 170.18 215.9 0)
			(effects
				(font
					(size 1.27 1.27)
				)
				(hide yes)
			)
		)
		(property "MPN" "PJE138K_R1_00001"
			(at 193.04 232.41 0)
			(effects
				(font
					(size 1.27 1.27)
					(thickness 0.15)
				)
				(justify left bottom)
				(hide yes)
			)
		)
		(property "Manufacturer" "PANJIT"
			(at 193.04 234.95 0)
			(effects
				(font
					(size 1.27 1.27)
					(thickness 0.15)
				)
				(justify left bottom)
				(hide yes)
			)
		)
		(property "Author" "Antmicro"
			(at 193.04 237.49 0)
			(effects
				(font
					(size 1.27 1.27)
					(thickness 0.15)
				)
				(justify left bottom)
				(hide yes)
			)
		)
		(property "License" "Apache-2.0"
			(at 193.04 240.03 0)
			(effects
				(font
					(size 1.27 1.27)
					(thickness 0.15)
				)
				(justify left bottom)
				(hide yes)
			)
		)
		(pin "1"
		)
		(pin "2"
		)
		(pin "3"
		)
		(instances
			(project "cm4-baseboard"
				(path ""
					(reference "Q210")
					(unit 1)
				)
			)
		)
	)
	(symbol
		(lib_id "antmicroTestPoints:TP_0.75mm_SMD")
		(at 167.64 215.9 180)
		(unit 1)
		(exclude_from_sim no)
		(in_bom no)
		(on_board yes)
		(dnp no)
		(property "Reference" "TP210"
			(at 165.1 213.36 0)
			(effects
				(font
					(size 1.27 1.27)
					(thickness 0.15)
				)
			)
		)
		(property "Value" "TP_0.75mm_SMD"
			(at 152.4 208.28 0)
			(effects
				(font
					(size 1.27 1.27)
					(thickness 0.15)
				)
				(justify left bottom)
				(hide yes)
			)
		)
		(property "Footprint" "antmicro-footprints:TP_SMD_0.75mm"
			(at 156.845 209.55 0)
			(effects
				(font
					(size 1.27 1.27)
					(thickness 0.15)
				)
				(justify left bottom)
				(hide yes)
			)
		)
		(property "Datasheet" ""
			(at 149.86 203.2 0)
			(effects
				(font
					(size 1.27 1.27)
					(thickness 0.15)
				)
				(justify left bottom)
				(hide yes)
			)
		)
		(property "Description" ""
			(at 167.64 215.9 0)
			(effects
				(font
					(size 1.27 1.27)
				)
				(hide yes)
			)
		)
		(property "Author" "Antmicro"
			(at 156.845 207.01 0)
			(effects
				(font
					(size 1.27 1.27)
					(thickness 0.15)
				)
				(justify left bottom)
				(hide yes)
			)
		)
		(property "License" "Apache-2.0"
			(at 156.845 204.47 0)
			(effects
				(font
					(size 1.27 1.27)
					(thickness 0.15)
				)
				(justify left bottom)
				(hide yes)
			)
		)
		(property "MPN" ""
			(at 156.845 204.47 0)
			(effects
				(font
					(size 1.27 1.27)
					(thickness 0.15)
				)
				(justify left bottom)
				(hide yes)
			)
		)
		(property "Manufacturer" ""
			(at 156.845 209.55 0)
			(effects
				(font
					(size 1.27 1.27)
					(thickness 0.15)
				)
				(justify left bottom)
				(hide yes)
			)
		)
		(pin "1"
		)
		(instances
			(project "cm4-baseboard"
				(path ""
					(reference "TP210")
					(unit 1)
				)
			)
		)
	)
	(symbol
		(lib_id "antmicropower:GND")
		(at 340.36 152.4 0)
		(unit 1)
		(exclude_from_sim no)
		(in_bom yes)
		(on_board yes)
		(dnp no)
		(fields_autoplaced yes)
		(property "Reference" "#PWR0226"
			(at 349.25 154.94 0)
			(effects
				(font
					(size 1.27 1.27)
					(thickness 0.15)
				)
				(justify left bottom)
				(hide yes)
			)
		)
		(property "Value" "GND"
			(at 338.3498 157.48 0)
			(effects
				(font
					(size 1.27 1.27)
					(thickness 0.15)
				)
				(justify left bottom)
			)
		)
		(property "Footprint" ""
			(at 349.25 160.02 0)
			(effects
				(font
					(size 1.27 1.27)
					(thickness 0.15)
				)
				(justify left bottom)
				(hide yes)
			)
		)
		(property "Datasheet" ""
			(at 349.25 165.1 0)
			(effects
				(font
					(size 1.27 1.27)
					(thickness 0.15)
				)
				(justify left bottom)
				(hide yes)
			)
		)
		(property "Description" ""
			(at 340.36 152.4 0)
			(effects
				(font
					(size 1.27 1.27)
				)
				(hide yes)
			)
		)
		(property "Author" "Antmicro"
			(at 349.25 160.02 0)
			(effects
				(font
					(size 1.27 1.27)
					(thickness 0.15)
				)
				(justify left bottom)
				(hide yes)
			)
		)
		(property "License" "Apache-2.0"
			(at 349.25 162.56 0)
			(effects
				(font
					(size 1.27 1.27)
					(thickness 0.15)
				)
				(justify left bottom)
				(hide yes)
			)
		)
		(pin "1"
		)
		(instances
			(project "cm4-baseboard"
				(path ""
					(reference "#PWR0226")
					(unit 1)
				)
			)
		)
	)
	(symbol
		(lib_id "antmicroResistors0402:R_0R_0402")
		(at 156.21 113.03 0)
		(unit 1)
		(exclude_from_sim no)
		(in_bom yes)
		(on_board yes)
		(dnp no)
		(property "Reference" "R222"
			(at 153.67 111.76 0)
			(effects
				(font
					(size 1.27 1.27)
				)
			)
		)
		(property "Value" "R_0R_0402"
			(at 156.21 116.84 0)
			(effects
				(font
					(size 1.27 1.27)
				)
				(justify left bottom)
				(hide yes)
			)
		)
		(property "Footprint" "antmicro-footprints:R_0402_1005Metric"
			(at 161.29 107.95 0)
			(effects
				(font
					(size 1.524 1.524)
				)
				(justify left bottom)
				(hide yes)
			)
		)
		(property "Datasheet" "https://industrial.panasonic.com/cdbs/www-data/pdf/RDA0000/AOA0000C301.pdf"
			(at 156.21 113.03 0)
			(effects
				(font
					(size 1.27 1.27)
				)
				(justify left bottom)
				(hide yes)
			)
		)
		(property "Description" ""
			(at 156.21 113.03 0)
			(effects
				(font
					(size 1.27 1.27)
				)
				(hide yes)
			)
		)
		(property "Manufacturer" "Panasonic"
			(at 161.29 102.87 0)
			(effects
				(font
					(size 1.524 1.524)
				)
				(justify left bottom)
				(hide yes)
			)
		)
		(property "MPN" "ERJ2GE0R00X"
			(at 161.29 105.41 0)
			(effects
				(font
					(size 1.524 1.524)
				)
				(justify left bottom)
				(hide yes)
			)
		)
		(property "Val" "0R"
			(at 162.56 111.76 0)
			(effects
				(font
					(size 1.27 1.27)
				)
			)
		)
		(property "License" "Apache-2.0"
			(at 176.53 138.43 0)
			(effects
				(font
					(size 1.27 1.27)
					(thickness 0.15)
				)
				(justify left bottom)
				(hide yes)
			)
		)
		(property "Author" "Antmicro"
			(at 176.53 140.97 0)
			(effects
				(font
					(size 1.27 1.27)
					(thickness 0.15)
				)
				(justify left bottom)
				(hide yes)
			)
		)
		(property "Tolerance" "~"
			(at 176.53 123.19 0)
			(effects
				(font
					(size 1.27 1.27)
				)
				(justify left bottom)
				(hide yes)
			)
		)
		(property "Current" "1A"
			(at 158.75 111.125 0)
			(effects
				(font
					(size 1.27 1.27)
					(thickness 0.15)
				)
				(hide yes)
			)
		)
		(pin "1"
		)
		(pin "2"
		)
		(instances
			(project "cm4-baseboard"
				(path ""
					(reference "R222")
					(unit 1)
				)
			)
		)
	)
	(symbol
		(lib_id "antmicropower:GND")
		(at 189.23 223.52 0)
		(unit 1)
		(exclude_from_sim no)
		(in_bom yes)
		(on_board yes)
		(dnp no)
		(property "Reference" "#PWR031"
			(at 198.12 226.06 0)
			(effects
				(font
					(size 1.27 1.27)
					(thickness 0.15)
				)
				(justify left bottom)
				(hide yes)
			)
		)
		(property "Value" "GND"
			(at 187.325 227.965 0)
			(effects
				(font
					(size 1.27 1.27)
					(thickness 0.15)
				)
				(justify left bottom)
			)
		)
		(property "Footprint" ""
			(at 198.12 231.14 0)
			(effects
				(font
					(size 1.27 1.27)
					(thickness 0.15)
				)
				(justify left bottom)
				(hide yes)
			)
		)
		(property "Datasheet" ""
			(at 198.12 236.22 0)
			(effects
				(font
					(size 1.27 1.27)
					(thickness 0.15)
				)
				(justify left bottom)
				(hide yes)
			)
		)
		(property "Description" ""
			(at 189.23 223.52 0)
			(effects
				(font
					(size 1.27 1.27)
				)
				(hide yes)
			)
		)
		(property "Author" "Antmicro"
			(at 198.12 231.14 0)
			(effects
				(font
					(size 1.27 1.27)
					(thickness 0.15)
				)
				(justify left bottom)
				(hide yes)
			)
		)
		(property "License" "Apache-2.0"
			(at 198.12 233.68 0)
			(effects
				(font
					(size 1.27 1.27)
					(thickness 0.15)
				)
				(justify left bottom)
				(hide yes)
			)
		)
		(pin "1"
		)
		(instances
			(project "cm4-baseboard"
				(path ""
					(reference "#PWR031")
					(unit 1)
				)
			)
		)
	)
	(symbol
		(lib_id "antmicroLEDIndicationDiscrete:LED_G_0603_KP-1608CGCK")
		(at 176.53 199.39 270)
		(mirror x)
		(unit 1)
		(exclude_from_sim no)
		(in_bom yes)
		(on_board yes)
		(dnp no)
		(property "Reference" "D205"
			(at 171.45 195.58 90)
			(effects
				(font
					(size 1.27 1.27)
					(thickness 0.15)
				)
			)
		)
		(property "Value" "LED_G_0603_KP-1608CGCK"
			(at 168.91 176.53 0)
			(effects
				(font
					(size 1.27 1.27)
					(thickness 0.15)
				)
				(justify left bottom)
				(hide yes)
			)
		)
		(property "Footprint" "antmicro-footprints:LED_0603_1608Metric_G"
			(at 166.37 176.53 0)
			(effects
				(font
					(size 1.27 1.27)
					(thickness 0.15)
				)
				(justify left bottom)
				(hide yes)
			)
		)
		(property "Datasheet" "http://www.kingbright.com/attachments/file/psearch//000/00/00/KP-1608CGCK(Ver.23B).pdf"
			(at 163.83 176.53 0)
			(effects
				(font
					(size 1.27 1.27)
					(thickness 0.15)
				)
				(justify left bottom)
				(hide yes)
			)
		)
		(property "Description" ""
			(at 176.53 199.39 0)
			(effects
				(font
					(size 1.27 1.27)
				)
				(hide yes)
			)
		)
		(property "MPN" "KP-1608CGCK"
			(at 161.29 176.53 0)
			(effects
				(font
					(size 1.27 1.27)
					(thickness 0.15)
				)
				(justify left bottom)
				(hide yes)
			)
		)
		(property "Manufacturer" "Kingbright"
			(at 158.75 176.53 0)
			(effects
				(font
					(size 1.27 1.27)
					(thickness 0.15)
				)
				(justify left bottom)
				(hide yes)
			)
		)
		(property "Color" "Green"
			(at 171.45 198.12 90)
			(effects
				(font
					(size 1.27 1.27)
				)
			)
		)
		(property "Author" "Antmicro"
			(at 156.21 176.53 0)
			(effects
				(font
					(size 1.27 1.27)
					(thickness 0.15)
				)
				(justify left bottom)
				(hide yes)
			)
		)
		(property "License" "Apache-2.0"
			(at 153.67 176.53 0)
			(effects
				(font
					(size 1.27 1.27)
					(thickness 0.15)
				)
				(justify left bottom)
				(hide yes)
			)
		)
		(pin "2"
		)
		(pin "1"
		)
		(instances
			(project "cm4-baseboard"
				(path ""
					(reference "D205")
					(unit 1)
				)
			)
		)
	)
	(symbol
		(lib_id "antmicroResistors0402:R_0R_0402")
		(at 26.67 140.97 0)
		(unit 1)
		(exclude_from_sim no)
		(in_bom yes)
		(on_board yes)
		(dnp no)
		(property "Reference" "R201"
			(at 29.21 135.89 0)
			(effects
				(font
					(size 1.27 1.27)
				)
			)
		)
		(property "Value" "R_0R_0402"
			(at 26.67 144.78 0)
			(effects
				(font
					(size 1.27 1.27)
				)
				(justify left bottom)
				(hide yes)
			)
		)
		(property "Footprint" "antmicro-footprints:R_0402_1005Metric"
			(at 31.75 135.89 0)
			(effects
				(font
					(size 1.524 1.524)
				)
				(justify left bottom)
				(hide yes)
			)
		)
		(property "Datasheet" "https://industrial.panasonic.com/cdbs/www-data/pdf/RDA0000/AOA0000C301.pdf"
			(at 26.67 140.97 0)
			(effects
				(font
					(size 1.27 1.27)
				)
				(justify left bottom)
				(hide yes)
			)
		)
		(property "Description" ""
			(at 26.67 140.97 0)
			(effects
				(font
					(size 1.27 1.27)
				)
				(hide yes)
			)
		)
		(property "Manufacturer" "Panasonic"
			(at 31.75 130.81 0)
			(effects
				(font
					(size 1.524 1.524)
				)
				(justify left bottom)
				(hide yes)
			)
		)
		(property "MPN" "ERJ2GE0R00X"
			(at 31.75 133.35 0)
			(effects
				(font
					(size 1.524 1.524)
				)
				(justify left bottom)
				(hide yes)
			)
		)
		(property "Val" "0R"
			(at 29.21 138.43 0)
			(effects
				(font
					(size 1.27 1.27)
				)
			)
		)
		(property "License" "Apache-2.0"
			(at 46.99 166.37 0)
			(effects
				(font
					(size 1.27 1.27)
					(thickness 0.15)
				)
				(justify left bottom)
				(hide yes)
			)
		)
		(property "Author" "Antmicro"
			(at 46.99 168.91 0)
			(effects
				(font
					(size 1.27 1.27)
					(thickness 0.15)
				)
				(justify left bottom)
				(hide yes)
			)
		)
		(property "Tolerance" "~"
			(at 46.99 151.13 0)
			(effects
				(font
					(size 1.27 1.27)
				)
				(justify left bottom)
				(hide yes)
			)
		)
		(property "Current" "1A"
			(at 29.21 139.065 0)
			(effects
				(font
					(size 1.27 1.27)
					(thickness 0.15)
				)
				(hide yes)
			)
		)
		(pin "1"
		)
		(pin "2"
		)
		(instances
			(project "cm4-baseboard"
				(path ""
					(reference "R201")
					(unit 1)
				)
			)
		)
	)
	(symbol
		(lib_id "antmicropower:GND")
		(at 114.3 246.38 0)
		(unit 1)
		(exclude_from_sim no)
		(in_bom yes)
		(on_board yes)
		(dnp no)
		(property "Reference" "#PWR0213"
			(at 114.3 252.73 0)
			(effects
				(font
					(size 1.27 1.27)
				)
				(justify left bottom)
				(hide yes)
			)
		)
		(property "Value" "GND"
			(at 114.3 250.19 0)
			(effects
				(font
					(size 1.27 1.27)
				)
			)
		)
		(property "Footprint" ""
			(at 123.19 254 0)
			(effects
				(font
					(size 1.27 1.27)
					(thickness 0.15)
				)
				(justify left bottom)
				(hide yes)
			)
		)
		(property "Datasheet" ""
			(at 123.19 259.08 0)
			(effects
				(font
					(size 1.27 1.27)
					(thickness 0.15)
				)
				(justify left bottom)
				(hide yes)
			)
		)
		(property "Description" ""
			(at 114.3 246.38 0)
			(effects
				(font
					(size 1.27 1.27)
				)
				(hide yes)
			)
		)
		(property "Author" "Antmicro"
			(at 123.19 254 0)
			(effects
				(font
					(size 1.27 1.27)
					(thickness 0.15)
				)
				(justify left bottom)
				(hide yes)
			)
		)
		(property "License" "Apache-2.0"
			(at 123.19 256.54 0)
			(effects
				(font
					(size 1.27 1.27)
					(thickness 0.15)
				)
				(justify left bottom)
				(hide yes)
			)
		)
		(pin "1"
		)
		(instances
			(project "cm4-baseboard"
				(path ""
					(reference "#PWR0213")
					(unit 1)
				)
			)
		)
	)
	(symbol
		(lib_id "antmicroTestPoints:TP_0.75mm_SMD")
		(at 90.17 158.75 0)
		(mirror x)
		(unit 1)
		(exclude_from_sim no)
		(in_bom no)
		(on_board yes)
		(dnp no)
		(property "Reference" "TP208"
			(at 94.615 158.75 0)
			(effects
				(font
					(size 1.27 1.27)
					(thickness 0.15)
				)
				(justify left)
			)
		)
		(property "Value" "TP_0.75mm_SMD"
			(at 105.41 151.13 0)
			(effects
				(font
					(size 1.27 1.27)
					(thickness 0.15)
				)
				(justify left bottom)
				(hide yes)
			)
		)
		(property "Footprint" "antmicro-footprints:TP_SMD_0.75mm"
			(at 100.965 152.4 0)
			(effects
				(font
					(size 1.27 1.27)
					(thickness 0.15)
				)
				(justify left bottom)
				(hide yes)
			)
		)
		(property "Datasheet" ""
			(at 107.95 146.05 0)
			(effects
				(font
					(size 1.27 1.27)
					(thickness 0.15)
				)
				(justify left bottom)
				(hide yes)
			)
		)
		(property "Description" ""
			(at 90.17 158.75 0)
			(effects
				(font
					(size 1.27 1.27)
				)
				(hide yes)
			)
		)
		(property "Author" "Antmicro"
			(at 100.965 149.86 0)
			(effects
				(font
					(size 1.27 1.27)
					(thickness 0.15)
				)
				(justify left bottom)
				(hide yes)
			)
		)
		(property "License" "Apache-2.0"
			(at 100.965 147.32 0)
			(effects
				(font
					(size 1.27 1.27)
					(thickness 0.15)
				)
				(justify left bottom)
				(hide yes)
			)
		)
		(property "MPN" ""
			(at 100.965 147.32 0)
			(effects
				(font
					(size 1.27 1.27)
					(thickness 0.15)
				)
				(justify left bottom)
				(hide yes)
			)
		)
		(property "Manufacturer" ""
			(at 100.965 152.4 0)
			(effects
				(font
					(size 1.27 1.27)
					(thickness 0.15)
				)
				(justify left bottom)
				(hide yes)
			)
		)
		(pin "1"
		)
		(instances
			(project "cm4-baseboard"
				(path ""
					(reference "TP208")
					(unit 1)
				)
			)
		)
	)
	(symbol
		(lib_id "antmicroLEDIndicationDiscrete:LED_G_0603_KP-1608CGCK")
		(at 92.71 59.69 0)
		(mirror x)
		(unit 1)
		(exclude_from_sim no)
		(in_bom yes)
		(on_board yes)
		(dnp no)
		(property "Reference" "D201"
			(at 95.25 57.15 0)
			(effects
				(font
					(size 1.27 1.27)
					(thickness 0.15)
				)
			)
		)
		(property "Value" "LED_G_0603_KP-1608CGCK"
			(at 115.57 52.07 0)
			(effects
				(font
					(size 1.27 1.27)
					(thickness 0.15)
				)
				(justify left bottom)
				(hide yes)
			)
		)
		(property "Footprint" "antmicro-footprints:LED_0603_1608Metric_G"
			(at 115.57 49.53 0)
			(effects
				(font
					(size 1.27 1.27)
					(thickness 0.15)
				)
				(justify left bottom)
				(hide yes)
			)
		)
		(property "Datasheet" "http://www.kingbright.com/attachments/file/psearch//000/00/00/KP-1608CGCK(Ver.23B).pdf"
			(at 115.57 46.99 0)
			(effects
				(font
					(size 1.27 1.27)
					(thickness 0.15)
				)
				(justify left bottom)
				(hide yes)
			)
		)
		(property "Description" ""
			(at 92.71 59.69 0)
			(effects
				(font
					(size 1.27 1.27)
				)
				(hide yes)
			)
		)
		(property "MPN" "KP-1608CGCK"
			(at 115.57 44.45 0)
			(effects
				(font
					(size 1.27 1.27)
					(thickness 0.15)
				)
				(justify left bottom)
				(hide yes)
			)
		)
		(property "Manufacturer" "Kingbright"
			(at 115.57 41.91 0)
			(effects
				(font
					(size 1.27 1.27)
					(thickness 0.15)
				)
				(justify left bottom)
				(hide yes)
			)
		)
		(property "Color" "Green"
			(at 95.25 63.5 0)
			(effects
				(font
					(size 1.27 1.27)
				)
			)
		)
		(property "Author" "Antmicro"
			(at 115.57 39.37 0)
			(effects
				(font
					(size 1.27 1.27)
					(thickness 0.15)
				)
				(justify left bottom)
				(hide yes)
			)
		)
		(property "License" "Apache-2.0"
			(at 115.57 36.83 0)
			(effects
				(font
					(size 1.27 1.27)
					(thickness 0.15)
				)
				(justify left bottom)
				(hide yes)
			)
		)
		(pin "2"
		)
		(pin "1"
		)
		(instances
			(project "cm4-baseboard"
				(path ""
					(reference "D201")
					(unit 1)
				)
			)
		)
	)
	(symbol
		(lib_id "antmicropower:GND")
		(at 168.91 223.52 0)
		(unit 1)
		(exclude_from_sim no)
		(in_bom yes)
		(on_board yes)
		(dnp no)
		(property "Reference" "#PWR027"
			(at 177.8 226.06 0)
			(effects
				(font
					(size 1.27 1.27)
					(thickness 0.15)
				)
				(justify left bottom)
				(hide yes)
			)
		)
		(property "Value" "GND"
			(at 167.005 227.965 0)
			(effects
				(font
					(size 1.27 1.27)
					(thickness 0.15)
				)
				(justify left bottom)
			)
		)
		(property "Footprint" ""
			(at 177.8 231.14 0)
			(effects
				(font
					(size 1.27 1.27)
					(thickness 0.15)
				)
				(justify left bottom)
				(hide yes)
			)
		)
		(property "Datasheet" ""
			(at 177.8 236.22 0)
			(effects
				(font
					(size 1.27 1.27)
					(thickness 0.15)
				)
				(justify left bottom)
				(hide yes)
			)
		)
		(property "Description" ""
			(at 168.91 223.52 0)
			(effects
				(font
					(size 1.27 1.27)
				)
				(hide yes)
			)
		)
		(property "Author" "Antmicro"
			(at 177.8 231.14 0)
			(effects
				(font
					(size 1.27 1.27)
					(thickness 0.15)
				)
				(justify left bottom)
				(hide yes)
			)
		)
		(property "License" "Apache-2.0"
			(at 177.8 233.68 0)
			(effects
				(font
					(size 1.27 1.27)
					(thickness 0.15)
				)
				(justify left bottom)
				(hide yes)
			)
		)
		(pin "1"
		)
		(instances
			(project "cm4-baseboard"
				(path ""
					(reference "#PWR027")
					(unit 1)
				)
			)
		)
	)
	(symbol
		(lib_id "antmicropower:+3V3")
		(at 271.78 144.78 0)
		(unit 1)
		(exclude_from_sim no)
		(in_bom yes)
		(on_board yes)
		(dnp no)
		(property "Reference" "#PWR0245"
			(at 287.02 147.32 0)
			(effects
				(font
					(size 1.27 1.27)
					(thickness 0.15)
				)
				(justify left bottom)
				(hide yes)
			)
		)
		(property "Value" "+3V3"
			(at 271.145 140.97 0)
			(effects
				(font
					(size 1.27 1.27)
					(thickness 0.15)
				)
			)
		)
		(property "Footprint" ""
			(at 287.02 152.4 0)
			(effects
				(font
					(size 1.27 1.27)
					(thickness 0.15)
				)
				(justify left bottom)
				(hide yes)
			)
		)
		(property "Datasheet" ""
			(at 287.02 154.94 0)
			(effects
				(font
					(size 1.27 1.27)
					(thickness 0.15)
				)
				(justify left bottom)
				(hide yes)
			)
		)
		(property "Description" ""
			(at 271.78 144.78 0)
			(effects
				(font
					(size 1.27 1.27)
				)
				(hide yes)
			)
		)
		(property "Author" "Antmicro"
			(at 287.02 152.4 0)
			(effects
				(font
					(size 1.27 1.27)
					(thickness 0.15)
				)
				(justify left bottom)
				(hide yes)
			)
		)
		(property "License" "Apache-2.0"
			(at 287.02 154.94 0)
			(effects
				(font
					(size 1.27 1.27)
					(thickness 0.15)
				)
				(justify left bottom)
				(hide yes)
			)
		)
		(pin "1"
		)
		(instances
			(project "cm4-baseboard"
				(path ""
					(reference "#PWR0245")
					(unit 1)
				)
			)
		)
	)
	(symbol
		(lib_id "antmicropower:GND")
		(at 260.35 275.59 0)
		(unit 1)
		(exclude_from_sim no)
		(in_bom yes)
		(on_board yes)
		(dnp no)
		(property "Reference" "#PWR0237"
			(at 269.24 278.13 0)
			(effects
				(font
					(size 1.27 1.27)
					(thickness 0.15)
				)
				(justify left bottom)
				(hide yes)
			)
		)
		(property "Value" "GND"
			(at 260.35 280.035 0)
			(effects
				(font
					(size 1.27 1.27)
					(thickness 0.15)
				)
			)
		)
		(property "Footprint" ""
			(at 269.24 283.21 0)
			(effects
				(font
					(size 1.27 1.27)
					(thickness 0.15)
				)
				(justify left bottom)
				(hide yes)
			)
		)
		(property "Datasheet" ""
			(at 269.24 288.29 0)
			(effects
				(font
					(size 1.27 1.27)
					(thickness 0.15)
				)
				(justify left bottom)
				(hide yes)
			)
		)
		(property "Description" ""
			(at 260.35 275.59 0)
			(effects
				(font
					(size 1.27 1.27)
				)
				(hide yes)
			)
		)
		(property "Author" "Antmicro"
			(at 269.24 283.21 0)
			(effects
				(font
					(size 1.27 1.27)
					(thickness 0.15)
				)
				(justify left bottom)
				(hide yes)
			)
		)
		(property "License" "Apache-2.0"
			(at 269.24 285.75 0)
			(effects
				(font
					(size 1.27 1.27)
					(thickness 0.15)
				)
				(justify left bottom)
				(hide yes)
			)
		)
		(pin "1"
		)
		(instances
			(project "cm4-baseboard"
				(path ""
					(reference "#PWR0237")
					(unit 1)
				)
			)
		)
	)
	(symbol
		(lib_id "antmicroResistors0402:R_10k_0402")
		(at 247.65 62.23 270)
		(mirror x)
		(unit 1)
		(exclude_from_sim no)
		(in_bom no)
		(on_board yes)
		(dnp yes)
		(property "Reference" "R232"
			(at 246.38 58.42 90)
			(effects
				(font
					(size 1.27 1.27)
					(thickness 0.15)
				)
				(justify right)
			)
		)
		(property "Value" "R_10k_0402"
			(at 234.95 41.91 0)
			(effects
				(font
					(size 1.27 1.27)
					(thickness 0.15)
				)
				(justify left bottom)
				(hide yes)
			)
		)
		(property "Footprint" "antmicro-footprints:R_0402_1005Metric"
			(at 232.41 41.91 0)
			(effects
				(font
					(size 1.27 1.27)
					(thickness 0.15)
				)
				(justify left bottom)
				(hide yes)
			)
		)
		(property "Datasheet" "https://www.bourns.com/docs/product-datasheets/cr.pdf"
			(at 229.87 41.91 0)
			(effects
				(font
					(size 1.27 1.27)
					(thickness 0.15)
				)
				(justify left bottom)
				(hide yes)
			)
		)
		(property "Description" ""
			(at 247.65 62.23 0)
			(effects
				(font
					(size 1.27 1.27)
				)
				(hide yes)
			)
		)
		(property "MPN" "CR0402-FX-1002GLF"
			(at 227.33 41.91 0)
			(effects
				(font
					(size 1.27 1.27)
					(thickness 0.15)
				)
				(justify left bottom)
				(hide yes)
			)
		)
		(property "Manufacturer" "Bourns"
			(at 224.79 41.91 0)
			(effects
				(font
					(size 1.27 1.27)
					(thickness 0.15)
				)
				(justify left bottom)
				(hide yes)
			)
		)
		(property "License" "Apache-2.0"
			(at 222.25 41.91 0)
			(effects
				(font
					(size 1.27 1.27)
					(thickness 0.15)
				)
				(justify left bottom)
				(hide yes)
			)
		)
		(property "Author" "Antmicro"
			(at 219.71 41.91 0)
			(effects
				(font
					(size 1.27 1.27)
					(thickness 0.15)
				)
				(justify left bottom)
				(hide yes)
			)
		)
		(property "Val" "10k"
			(at 246.38 60.96 90)
			(effects
				(font
					(size 1.27 1.27)
					(thickness 0.15)
				)
				(justify right)
			)
		)
		(property "Tolerance" "1%"
			(at 237.49 41.91 0)
			(effects
				(font
					(size 1.27 1.27)
				)
				(justify left bottom)
				(hide yes)
			)
		)
		(pin "1"
		)
		(pin "2"
		)
		(instances
			(project "cm4-baseboard"
				(path ""
					(reference "R232")
					(unit 1)
				)
			)
		)
	)
	(symbol
		(lib_id "antmicroTestPoints:TP_0.75mm_SMD")
		(at 90.17 148.59 0)
		(mirror x)
		(unit 1)
		(exclude_from_sim no)
		(in_bom no)
		(on_board yes)
		(dnp no)
		(property "Reference" "TP206"
			(at 94.615 148.59 0)
			(effects
				(font
					(size 1.27 1.27)
					(thickness 0.15)
				)
				(justify left)
			)
		)
		(property "Value" "TP_0.75mm_SMD"
			(at 105.41 140.97 0)
			(effects
				(font
					(size 1.27 1.27)
					(thickness 0.15)
				)
				(justify left bottom)
				(hide yes)
			)
		)
		(property "Footprint" "antmicro-footprints:TP_SMD_0.75mm"
			(at 100.965 142.24 0)
			(effects
				(font
					(size 1.27 1.27)
					(thickness 0.15)
				)
				(justify left bottom)
				(hide yes)
			)
		)
		(property "Datasheet" ""
			(at 107.95 135.89 0)
			(effects
				(font
					(size 1.27 1.27)
					(thickness 0.15)
				)
				(justify left bottom)
				(hide yes)
			)
		)
		(property "Description" ""
			(at 90.17 148.59 0)
			(effects
				(font
					(size 1.27 1.27)
				)
				(hide yes)
			)
		)
		(property "Author" "Antmicro"
			(at 100.965 139.7 0)
			(effects
				(font
					(size 1.27 1.27)
					(thickness 0.15)
				)
				(justify left bottom)
				(hide yes)
			)
		)
		(property "License" "Apache-2.0"
			(at 100.965 137.16 0)
			(effects
				(font
					(size 1.27 1.27)
					(thickness 0.15)
				)
				(justify left bottom)
				(hide yes)
			)
		)
		(property "MPN" ""
			(at 100.965 137.16 0)
			(effects
				(font
					(size 1.27 1.27)
					(thickness 0.15)
				)
				(justify left bottom)
				(hide yes)
			)
		)
		(property "Manufacturer" ""
			(at 100.965 142.24 0)
			(effects
				(font
					(size 1.27 1.27)
					(thickness 0.15)
				)
				(justify left bottom)
				(hide yes)
			)
		)
		(pin "1"
		)
		(instances
			(project "cm4-baseboard"
				(path ""
					(reference "TP206")
					(unit 1)
				)
			)
		)
	)
	(symbol
		(lib_id "antmicropower:+3V3")
		(at 251.46 35.56 0)
		(unit 1)
		(exclude_from_sim no)
		(in_bom yes)
		(on_board yes)
		(dnp no)
		(property "Reference" "#PWR0238"
			(at 266.7 35.56 0)
			(effects
				(font
					(size 1.27 1.27)
					(thickness 0.15)
				)
				(justify left bottom)
				(hide yes)
			)
		)
		(property "Value" "+3V3"
			(at 248.92 31.75 0)
			(effects
				(font
					(size 1.27 1.27)
					(thickness 0.15)
				)
				(justify left)
			)
		)
		(property "Footprint" ""
			(at 266.7 43.18 0)
			(effects
				(font
					(size 1.27 1.27)
					(thickness 0.15)
				)
				(justify left bottom)
				(hide yes)
			)
		)
		(property "Datasheet" ""
			(at 266.7 45.72 0)
			(effects
				(font
					(size 1.27 1.27)
					(thickness 0.15)
				)
				(justify left bottom)
				(hide yes)
			)
		)
		(property "Description" ""
			(at 251.46 35.56 0)
			(effects
				(font
					(size 1.27 1.27)
				)
				(hide yes)
			)
		)
		(property "Author" "Antmicro"
			(at 266.7 38.1 0)
			(effects
				(font
					(size 1.27 1.27)
					(thickness 0.15)
				)
				(justify left bottom)
				(hide yes)
			)
		)
		(property "License" "Apache-2.0"
			(at 266.7 40.64 0)
			(effects
				(font
					(size 1.27 1.27)
					(thickness 0.15)
				)
				(justify left bottom)
				(hide yes)
			)
		)
		(pin "1"
		)
		(instances
			(project "cm4-baseboard"
				(path ""
					(reference "#PWR0238")
					(unit 1)
				)
			)
		)
	)
	(symbol
		(lib_id "antmicroResistors0402:R_10k_0402")
		(at 254 44.45 90)
		(unit 1)
		(exclude_from_sim no)
		(in_bom yes)
		(on_board yes)
		(dnp no)
		(fields_autoplaced yes)
		(property "Reference" "R235"
			(at 256.54 40.6399 90)
			(effects
				(font
					(size 1.27 1.27)
					(thickness 0.15)
				)
				(justify right)
			)
		)
		(property "Value" "R_10k_0402"
			(at 266.7 24.13 0)
			(effects
				(font
					(size 1.27 1.27)
					(thickness 0.15)
				)
				(justify left bottom)
				(hide yes)
			)
		)
		(property "Footprint" "antmicro-footprints:R_0402_1005Metric"
			(at 269.24 24.13 0)
			(effects
				(font
					(size 1.27 1.27)
					(thickness 0.15)
				)
				(justify left bottom)
				(hide yes)
			)
		)
		(property "Datasheet" "https://www.bourns.com/docs/product-datasheets/cr.pdf"
			(at 271.78 24.13 0)
			(effects
				(font
					(size 1.27 1.27)
					(thickness 0.15)
				)
				(justify left bottom)
				(hide yes)
			)
		)
		(property "Description" ""
			(at 254 44.45 0)
			(effects
				(font
					(size 1.27 1.27)
				)
				(hide yes)
			)
		)
		(property "MPN" "CR0402-FX-1002GLF"
			(at 274.32 24.13 0)
			(effects
				(font
					(size 1.27 1.27)
					(thickness 0.15)
				)
				(justify left bottom)
				(hide yes)
			)
		)
		(property "Manufacturer" "Bourns"
			(at 276.86 24.13 0)
			(effects
				(font
					(size 1.27 1.27)
					(thickness 0.15)
				)
				(justify left bottom)
				(hide yes)
			)
		)
		(property "License" "Apache-2.0"
			(at 279.4 24.13 0)
			(effects
				(font
					(size 1.27 1.27)
					(thickness 0.15)
				)
				(justify left bottom)
				(hide yes)
			)
		)
		(property "Author" "Antmicro"
			(at 281.94 24.13 0)
			(effects
				(font
					(size 1.27 1.27)
					(thickness 0.15)
				)
				(justify left bottom)
				(hide yes)
			)
		)
		(property "Val" "10k"
			(at 256.54 43.1799 90)
			(effects
				(font
					(size 1.27 1.27)
					(thickness 0.15)
				)
				(justify right)
			)
		)
		(property "Tolerance" "1%"
			(at 264.16 24.13 0)
			(effects
				(font
					(size 1.27 1.27)
				)
				(justify left bottom)
				(hide yes)
			)
		)
		(pin "1"
		)
		(pin "2"
		)
		(instances
			(project "cm4-baseboard"
				(path ""
					(reference "R235")
					(unit 1)
				)
			)
		)
	)
	(symbol
		(lib_id "antmicropower:PWR_FLAG")
		(at 41.91 144.78 0)
		(unit 1)
		(exclude_from_sim no)
		(in_bom yes)
		(on_board yes)
		(dnp no)
		(property "Reference" "#FLG014"
			(at 41.91 142.875 0)
			(effects
				(font
					(size 1.27 1.27)
				)
				(hide yes)
			)
		)
		(property "Value" "PWR_FLAG"
			(at 48.26 142.24 0)
			(effects
				(font
					(size 1.27 1.27)
				)
			)
		)
		(property "Footprint" ""
			(at 41.91 144.78 0)
			(effects
				(font
					(size 1.27 1.27)
				)
				(hide yes)
			)
		)
		(property "Datasheet" ""
			(at 41.91 144.78 0)
			(effects
				(font
					(size 1.27 1.27)
				)
				(hide yes)
			)
		)
		(property "Description" ""
			(at 41.91 144.78 0)
			(effects
				(font
					(size 1.27 1.27)
				)
				(hide yes)
			)
		)
		(pin "1"
		)
		(instances
			(project "cm4-baseboard"
				(path ""
					(reference "#FLG014")
					(unit 1)
				)
			)
		)
	)
	(symbol
		(lib_id "antmicropower:+3V3")
		(at 247.65 55.88 0)
		(unit 1)
		(exclude_from_sim no)
		(in_bom yes)
		(on_board yes)
		(dnp no)
		(property "Reference" "#PWR0235"
			(at 262.89 55.88 0)
			(effects
				(font
					(size 1.27 1.27)
					(thickness 0.15)
				)
				(justify left bottom)
				(hide yes)
			)
		)
		(property "Value" "+3V3"
			(at 245.11 52.07 0)
			(effects
				(font
					(size 1.27 1.27)
					(thickness 0.15)
				)
				(justify left)
			)
		)
		(property "Footprint" ""
			(at 262.89 63.5 0)
			(effects
				(font
					(size 1.27 1.27)
					(thickness 0.15)
				)
				(justify left bottom)
				(hide yes)
			)
		)
		(property "Datasheet" ""
			(at 262.89 66.04 0)
			(effects
				(font
					(size 1.27 1.27)
					(thickness 0.15)
				)
				(justify left bottom)
				(hide yes)
			)
		)
		(property "Description" ""
			(at 247.65 55.88 0)
			(effects
				(font
					(size 1.27 1.27)
				)
				(hide yes)
			)
		)
		(property "Author" "Antmicro"
			(at 262.89 58.42 0)
			(effects
				(font
					(size 1.27 1.27)
					(thickness 0.15)
				)
				(justify left bottom)
				(hide yes)
			)
		)
		(property "License" "Apache-2.0"
			(at 262.89 60.96 0)
			(effects
				(font
					(size 1.27 1.27)
					(thickness 0.15)
				)
				(justify left bottom)
				(hide yes)
			)
		)
		(pin "1"
		)
		(instances
			(project "cm4-baseboard"
				(path ""
					(reference "#PWR0235")
					(unit 1)
				)
			)
		)
	)
	(symbol
		(lib_id "antmicroResistors0402:R_0R_0402")
		(at 156.21 97.79 0)
		(unit 1)
		(exclude_from_sim no)
		(in_bom yes)
		(on_board yes)
		(dnp no)
		(property "Reference" "R218"
			(at 153.67 96.52 0)
			(effects
				(font
					(size 1.27 1.27)
				)
			)
		)
		(property "Value" "R_0R_0402"
			(at 156.21 101.6 0)
			(effects
				(font
					(size 1.27 1.27)
				)
				(justify left bottom)
				(hide yes)
			)
		)
		(property "Footprint" "antmicro-footprints:R_0402_1005Metric"
			(at 161.29 92.71 0)
			(effects
				(font
					(size 1.524 1.524)
				)
				(justify left bottom)
				(hide yes)
			)
		)
		(property "Datasheet" "https://industrial.panasonic.com/cdbs/www-data/pdf/RDA0000/AOA0000C301.pdf"
			(at 156.21 97.79 0)
			(effects
				(font
					(size 1.27 1.27)
				)
				(justify left bottom)
				(hide yes)
			)
		)
		(property "Description" ""
			(at 156.21 97.79 0)
			(effects
				(font
					(size 1.27 1.27)
				)
				(hide yes)
			)
		)
		(property "Manufacturer" "Panasonic"
			(at 161.29 87.63 0)
			(effects
				(font
					(size 1.524 1.524)
				)
				(justify left bottom)
				(hide yes)
			)
		)
		(property "MPN" "ERJ2GE0R00X"
			(at 161.29 90.17 0)
			(effects
				(font
					(size 1.524 1.524)
				)
				(justify left bottom)
				(hide yes)
			)
		)
		(property "Val" "0R"
			(at 162.56 96.52 0)
			(effects
				(font
					(size 1.27 1.27)
				)
			)
		)
		(property "License" "Apache-2.0"
			(at 176.53 123.19 0)
			(effects
				(font
					(size 1.27 1.27)
					(thickness 0.15)
				)
				(justify left bottom)
				(hide yes)
			)
		)
		(property "Author" "Antmicro"
			(at 176.53 125.73 0)
			(effects
				(font
					(size 1.27 1.27)
					(thickness 0.15)
				)
				(justify left bottom)
				(hide yes)
			)
		)
		(property "Tolerance" "~"
			(at 176.53 107.95 0)
			(effects
				(font
					(size 1.27 1.27)
				)
				(justify left bottom)
				(hide yes)
			)
		)
		(property "Current" "1A"
			(at 158.75 95.885 0)
			(effects
				(font
					(size 1.27 1.27)
					(thickness 0.15)
				)
				(hide yes)
			)
		)
		(pin "1"
		)
		(pin "2"
		)
		(instances
			(project "cm4-baseboard"
				(path ""
					(reference "R218")
					(unit 1)
				)
			)
		)
	)
	(symbol
		(lib_id "antmicroResistors0402:R_10k_0402")
		(at 255.27 62.23 270)
		(mirror x)
		(unit 1)
		(exclude_from_sim no)
		(in_bom no)
		(on_board yes)
		(dnp yes)
		(property "Reference" "R236"
			(at 254 58.42 90)
			(effects
				(font
					(size 1.27 1.27)
					(thickness 0.15)
				)
				(justify right)
			)
		)
		(property "Value" "R_10k_0402"
			(at 242.57 41.91 0)
			(effects
				(font
					(size 1.27 1.27)
					(thickness 0.15)
				)
				(justify left bottom)
				(hide yes)
			)
		)
		(property "Footprint" "antmicro-footprints:R_0402_1005Metric"
			(at 240.03 41.91 0)
			(effects
				(font
					(size 1.27 1.27)
					(thickness 0.15)
				)
				(justify left bottom)
				(hide yes)
			)
		)
		(property "Datasheet" "https://www.bourns.com/docs/product-datasheets/cr.pdf"
			(at 237.49 41.91 0)
			(effects
				(font
					(size 1.27 1.27)
					(thickness 0.15)
				)
				(justify left bottom)
				(hide yes)
			)
		)
		(property "Description" ""
			(at 255.27 62.23 0)
			(effects
				(font
					(size 1.27 1.27)
				)
				(hide yes)
			)
		)
		(property "MPN" "CR0402-FX-1002GLF"
			(at 234.95 41.91 0)
			(effects
				(font
					(size 1.27 1.27)
					(thickness 0.15)
				)
				(justify left bottom)
				(hide yes)
			)
		)
		(property "Manufacturer" "Bourns"
			(at 232.41 41.91 0)
			(effects
				(font
					(size 1.27 1.27)
					(thickness 0.15)
				)
				(justify left bottom)
				(hide yes)
			)
		)
		(property "License" "Apache-2.0"
			(at 229.87 41.91 0)
			(effects
				(font
					(size 1.27 1.27)
					(thickness 0.15)
				)
				(justify left bottom)
				(hide yes)
			)
		)
		(property "Author" "Antmicro"
			(at 227.33 41.91 0)
			(effects
				(font
					(size 1.27 1.27)
					(thickness 0.15)
				)
				(justify left bottom)
				(hide yes)
			)
		)
		(property "Val" "10k"
			(at 254 60.96 90)
			(effects
				(font
					(size 1.27 1.27)
					(thickness 0.15)
				)
				(justify right)
			)
		)
		(property "Tolerance" "1%"
			(at 245.11 41.91 0)
			(effects
				(font
					(size 1.27 1.27)
				)
				(justify left bottom)
				(hide yes)
			)
		)
		(pin "1"
		)
		(pin "2"
		)
		(instances
			(project "cm4-baseboard"
				(path ""
					(reference "R236")
					(unit 1)
				)
			)
		)
	)
	(symbol
		(lib_id "antmicroTransistorsFETsMOSFETsSingle:PJE138K")
		(at 142.24 238.76 0)
		(unit 1)
		(exclude_from_sim no)
		(in_bom yes)
		(on_board yes)
		(dnp no)
		(fields_autoplaced yes)
		(property "Reference" "Q209"
			(at 153.67 234.9499 0)
			(effects
				(font
					(size 1.27 1.27)
				)
				(justify left)
			)
		)
		(property "Value" "PJE138K"
			(at 153.67 237.4899 0)
			(effects
				(font
					(size 1.27 1.27)
				)
				(justify left)
			)
		)
		(property "Footprint" "antmicro-footprints:SOT-523"
			(at 147.32 233.68 0)
			(effects
				(font
					(size 1.524 1.524)
				)
				(justify left bottom)
				(hide yes)
			)
		)
		(property "Datasheet" "https://www.mouser.com/datasheet/2/1057/PJE138K-1876698.pdf"
			(at 147.32 231.14 0)
			(effects
				(font
					(size 1.524 1.524)
				)
				(justify left bottom)
				(hide yes)
			)
		)
		(property "Description" ""
			(at 142.24 238.76 0)
			(effects
				(font
					(size 1.27 1.27)
				)
				(hide yes)
			)
		)
		(property "MPN" "PJE138K_R1_00001"
			(at 158.75 228.6 0)
			(effects
				(font
					(size 1.524 1.524)
				)
				(justify left bottom)
				(hide yes)
			)
		)
		(property "Manufacturer" "PANJIT"
			(at 147.32 228.6 0)
			(effects
				(font
					(size 1.524 1.524)
				)
				(justify left bottom)
				(hide yes)
			)
		)
		(property "Author" "Antmicro"
			(at 165.1 260.35 0)
			(effects
				(font
					(size 1.27 1.27)
					(thickness 0.15)
				)
				(justify left bottom)
				(hide yes)
			)
		)
		(property "License" "Apache-2.0"
			(at 165.1 262.89 0)
			(effects
				(font
					(size 1.27 1.27)
					(thickness 0.15)
				)
				(justify left bottom)
				(hide yes)
			)
		)
		(pin "1"
		)
		(pin "2"
		)
		(pin "3"
		)
		(instances
			(project "cm4-baseboard"
				(path ""
					(reference "Q209")
					(unit 1)
				)
			)
		)
	)
	(symbol
		(lib_id "antmicroResistors0402:R_0R_0402")
		(at 58.42 128.27 180)
		(unit 1)
		(exclude_from_sim no)
		(in_bom no)
		(on_board yes)
		(dnp yes)
		(property "Reference" "R206"
			(at 55.88 123.19 0)
			(effects
				(font
					(size 1.27 1.27)
				)
			)
		)
		(property "Value" "R_0R_0402"
			(at 58.42 124.46 0)
			(effects
				(font
					(size 1.27 1.27)
				)
				(justify left bottom)
				(hide yes)
			)
		)
		(property "Footprint" "antmicro-footprints:R_0402_1005Metric"
			(at 53.34 133.35 0)
			(effects
				(font
					(size 1.524 1.524)
				)
				(justify left bottom)
				(hide yes)
			)
		)
		(property "Datasheet" "https://industrial.panasonic.com/cdbs/www-data/pdf/RDA0000/AOA0000C301.pdf"
			(at 58.42 128.27 0)
			(effects
				(font
					(size 1.27 1.27)
				)
				(justify left bottom)
				(hide yes)
			)
		)
		(property "Description" ""
			(at 58.42 128.27 0)
			(effects
				(font
					(size 1.27 1.27)
				)
				(hide yes)
			)
		)
		(property "Manufacturer" "Panasonic"
			(at 53.34 138.43 0)
			(effects
				(font
					(size 1.524 1.524)
				)
				(justify left bottom)
				(hide yes)
			)
		)
		(property "MPN" "ERJ2GE0R00X"
			(at 53.34 135.89 0)
			(effects
				(font
					(size 1.524 1.524)
				)
				(justify left bottom)
				(hide yes)
			)
		)
		(property "Val" "0R"
			(at 55.88 125.73 0)
			(effects
				(font
					(size 1.27 1.27)
				)
			)
		)
		(property "License" "Apache-2.0"
			(at 38.1 102.87 0)
			(effects
				(font
					(size 1.27 1.27)
					(thickness 0.15)
				)
				(justify left bottom)
				(hide yes)
			)
		)
		(property "Author" "Antmicro"
			(at 38.1 100.33 0)
			(effects
				(font
					(size 1.27 1.27)
					(thickness 0.15)
				)
				(justify left bottom)
				(hide yes)
			)
		)
		(property "Tolerance" "~"
			(at 38.1 118.11 0)
			(effects
				(font
					(size 1.27 1.27)
				)
				(justify left bottom)
				(hide yes)
			)
		)
		(property "Current" "1A"
			(at 55.88 130.175 0)
			(effects
				(font
					(size 1.27 1.27)
					(thickness 0.15)
				)
				(hide yes)
			)
		)
		(pin "1"
		)
		(pin "2"
		)
		(instances
			(project "cm4-baseboard"
				(path ""
					(reference "R206")
					(unit 1)
				)
			)
		)
	)
	(symbol
		(lib_id "antmicropower:GND")
		(at 349.25 245.11 0)
		(unit 1)
		(exclude_from_sim no)
		(in_bom yes)
		(on_board yes)
		(dnp no)
		(property "Reference" "#PWR0264"
			(at 358.14 247.65 0)
			(effects
				(font
					(size 1.27 1.27)
					(thickness 0.15)
				)
				(justify left bottom)
				(hide yes)
			)
		)
		(property "Value" "GND"
			(at 349.25 248.92 0)
			(effects
				(font
					(size 1.27 1.27)
					(thickness 0.15)
				)
			)
		)
		(property "Footprint" ""
			(at 358.14 252.73 0)
			(effects
				(font
					(size 1.27 1.27)
					(thickness 0.15)
				)
				(justify left bottom)
				(hide yes)
			)
		)
		(property "Datasheet" ""
			(at 358.14 257.81 0)
			(effects
				(font
					(size 1.27 1.27)
					(thickness 0.15)
				)
				(justify left bottom)
				(hide yes)
			)
		)
		(property "Description" ""
			(at 349.25 245.11 0)
			(effects
				(font
					(size 1.27 1.27)
				)
				(hide yes)
			)
		)
		(property "Author" "Antmicro"
			(at 358.14 252.73 0)
			(effects
				(font
					(size 1.27 1.27)
					(thickness 0.15)
				)
				(justify left bottom)
				(hide yes)
			)
		)
		(property "License" "Apache-2.0"
			(at 358.14 255.27 0)
			(effects
				(font
					(size 1.27 1.27)
					(thickness 0.15)
				)
				(justify left bottom)
				(hide yes)
			)
		)
		(pin "1"
		)
		(instances
			(project "cm4-baseboard"
				(path ""
					(reference "#PWR0264")
					(unit 1)
				)
			)
		)
	)
	(symbol
		(lib_id "antmicroResistors0402:R_100k_0402")
		(at 168.91 222.25 90)
		(unit 1)
		(exclude_from_sim no)
		(in_bom yes)
		(on_board yes)
		(dnp no)
		(property "Reference" "R262"
			(at 162.56 218.44 90)
			(effects
				(font
					(size 1.27 1.27)
				)
				(justify right)
			)
		)
		(property "Value" "R_100k_0402"
			(at 172.72 222.25 0)
			(effects
				(font
					(size 1.27 1.27)
				)
				(justify left bottom)
				(hide yes)
			)
		)
		(property "Footprint" "antmicro-footprints:R_0402_1005Metric"
			(at 163.83 217.17 0)
			(effects
				(font
					(size 1.524 1.524)
				)
				(justify left bottom)
				(hide yes)
			)
		)
		(property "Datasheet" "https://www.bourns.com/docs/product-datasheets/cr.pdf"
			(at 168.91 222.25 0)
			(effects
				(font
					(size 1.27 1.27)
				)
				(justify left bottom)
				(hide yes)
			)
		)
		(property "Description" ""
			(at 168.91 222.25 0)
			(effects
				(font
					(size 1.27 1.27)
				)
				(hide yes)
			)
		)
		(property "Manufacturer" "Bourns"
			(at 158.75 217.17 0)
			(effects
				(font
					(size 1.524 1.524)
				)
				(justify left bottom)
				(hide yes)
			)
		)
		(property "MPN" "CR0402-FX-1003GLF"
			(at 161.29 217.17 0)
			(effects
				(font
					(size 1.524 1.524)
				)
				(justify left bottom)
				(hide yes)
			)
		)
		(property "Val" "100k"
			(at 162.56 220.98 90)
			(effects
				(font
					(size 1.27 1.27)
				)
				(justify right)
			)
		)
		(property "License" "Apache-2.0"
			(at 194.31 201.93 0)
			(effects
				(font
					(size 1.27 1.27)
					(thickness 0.15)
				)
				(justify left bottom)
				(hide yes)
			)
		)
		(property "Author" "Antmicro"
			(at 196.85 201.93 0)
			(effects
				(font
					(size 1.27 1.27)
					(thickness 0.15)
				)
				(justify left bottom)
				(hide yes)
			)
		)
		(property "Tolerance" "1%"
			(at 179.07 201.93 0)
			(effects
				(font
					(size 1.27 1.27)
				)
				(justify left bottom)
				(hide yes)
			)
		)
		(pin "1"
		)
		(pin "2"
		)
		(instances
			(project "cm4-baseboard"
				(path ""
					(reference "R262")
					(unit 1)
				)
			)
		)
	)
	(symbol
		(lib_id "antmicroResistors0402:R_0R_0402")
		(at 81.28 171.45 0)
		(unit 1)
		(exclude_from_sim no)
		(in_bom no)
		(on_board yes)
		(dnp yes)
		(property "Reference" "R209"
			(at 83.82 173.99 0)
			(effects
				(font
					(size 1.27 1.27)
				)
			)
		)
		(property "Value" "R_0R_0402"
			(at 81.28 175.26 0)
			(effects
				(font
					(size 1.27 1.27)
				)
				(justify left bottom)
				(hide yes)
			)
		)
		(property "Footprint" "antmicro-footprints:R_0402_1005Metric"
			(at 86.36 166.37 0)
			(effects
				(font
					(size 1.524 1.524)
				)
				(justify left bottom)
				(hide yes)
			)
		)
		(property "Datasheet" "https://industrial.panasonic.com/cdbs/www-data/pdf/RDA0000/AOA0000C301.pdf"
			(at 81.28 171.45 0)
			(effects
				(font
					(size 1.27 1.27)
				)
				(justify left bottom)
				(hide yes)
			)
		)
		(property "Description" ""
			(at 81.28 171.45 0)
			(effects
				(font
					(size 1.27 1.27)
				)
				(hide yes)
			)
		)
		(property "Manufacturer" "Panasonic"
			(at 86.36 161.29 0)
			(effects
				(font
					(size 1.524 1.524)
				)
				(justify left bottom)
				(hide yes)
			)
		)
		(property "MPN" "ERJ2GE0R00X"
			(at 86.36 163.83 0)
			(effects
				(font
					(size 1.524 1.524)
				)
				(justify left bottom)
				(hide yes)
			)
		)
		(property "Val" "0R"
			(at 83.82 176.53 0)
			(effects
				(font
					(size 1.27 1.27)
				)
			)
		)
		(property "License" "Apache-2.0"
			(at 101.6 196.85 0)
			(effects
				(font
					(size 1.27 1.27)
					(thickness 0.15)
				)
				(justify left bottom)
				(hide yes)
			)
		)
		(property "Author" "Antmicro"
			(at 101.6 199.39 0)
			(effects
				(font
					(size 1.27 1.27)
					(thickness 0.15)
				)
				(justify left bottom)
				(hide yes)
			)
		)
		(property "Tolerance" "~"
			(at 101.6 181.61 0)
			(effects
				(font
					(size 1.27 1.27)
				)
				(justify left bottom)
				(hide yes)
			)
		)
		(property "Current" "1A"
			(at 83.82 169.545 0)
			(effects
				(font
					(size 1.27 1.27)
					(thickness 0.15)
				)
				(hide yes)
			)
		)
		(pin "1"
		)
		(pin "2"
		)
		(instances
			(project "cm4-baseboard"
				(path ""
					(reference "R209")
					(unit 1)
				)
			)
		)
	)
	(symbol
		(lib_id "antmicropower:GND")
		(at 340.36 134.62 0)
		(unit 1)
		(exclude_from_sim no)
		(in_bom yes)
		(on_board yes)
		(dnp no)
		(fields_autoplaced yes)
		(property "Reference" "#PWR0224"
			(at 349.25 137.16 0)
			(effects
				(font
					(size 1.27 1.27)
					(thickness 0.15)
				)
				(justify left bottom)
				(hide yes)
			)
		)
		(property "Value" "GND"
			(at 338.3498 139.7 0)
			(effects
				(font
					(size 1.27 1.27)
					(thickness 0.15)
				)
				(justify left bottom)
			)
		)
		(property "Footprint" ""
			(at 349.25 142.24 0)
			(effects
				(font
					(size 1.27 1.27)
					(thickness 0.15)
				)
				(justify left bottom)
				(hide yes)
			)
		)
		(property "Datasheet" ""
			(at 349.25 147.32 0)
			(effects
				(font
					(size 1.27 1.27)
					(thickness 0.15)
				)
				(justify left bottom)
				(hide yes)
			)
		)
		(property "Description" ""
			(at 340.36 134.62 0)
			(effects
				(font
					(size 1.27 1.27)
				)
				(hide yes)
			)
		)
		(property "Author" "Antmicro"
			(at 349.25 142.24 0)
			(effects
				(font
					(size 1.27 1.27)
					(thickness 0.15)
				)
				(justify left bottom)
				(hide yes)
			)
		)
		(property "License" "Apache-2.0"
			(at 349.25 144.78 0)
			(effects
				(font
					(size 1.27 1.27)
					(thickness 0.15)
				)
				(justify left bottom)
				(hide yes)
			)
		)
		(pin "1"
		)
		(instances
			(project "cm4-baseboard"
				(path ""
					(reference "#PWR0224")
					(unit 1)
				)
			)
		)
	)
	(symbol
		(lib_id "antmicroSlideSwitches:CAS-120TA")
		(at 120.65 269.24 0)
		(mirror y)
		(unit 1)
		(exclude_from_sim no)
		(in_bom yes)
		(on_board yes)
		(dnp no)
		(fields_autoplaced yes)
		(property "Reference" "S203"
			(at 114.3 260.35 0)
			(effects
				(font
					(size 1.27 1.27)
					(thickness 0.15)
				)
			)
		)
		(property "Value" "CAS-120TA"
			(at 114.3 262.89 0)
			(effects
				(font
					(size 1.27 1.27)
					(thickness 0.15)
				)
				(hide yes)
			)
		)
		(property "Footprint" "antmicro-footprints:Switch_Slide_CAS-120TA"
			(at 95.25 276.86 0)
			(effects
				(font
					(size 1.27 1.27)
					(thickness 0.15)
				)
				(justify left bottom)
				(hide yes)
			)
		)
		(property "Datasheet" "https://www.nidec-components.com/e/catalog/switch/cas.pdf"
			(at 95.25 279.4 0)
			(effects
				(font
					(size 1.27 1.27)
					(thickness 0.15)
				)
				(justify left bottom)
				(hide yes)
			)
		)
		(property "Description" ""
			(at 120.65 269.24 0)
			(effects
				(font
					(size 1.27 1.27)
				)
				(hide yes)
			)
		)
		(property "MPN" "CAS-120TA"
			(at 114.3 262.89 0)
			(effects
				(font
					(size 1.27 1.27)
					(thickness 0.15)
				)
			)
		)
		(property "Manufacturer" "Nidec Components"
			(at 95.25 284.48 0)
			(effects
				(font
					(size 1.27 1.27)
					(thickness 0.15)
				)
				(justify left bottom)
				(hide yes)
			)
		)
		(property "Author" "Antmicro"
			(at 95.25 287.02 0)
			(effects
				(font
					(size 1.27 1.27)
					(thickness 0.15)
				)
				(justify left bottom)
				(hide yes)
			)
		)
		(property "License" "Apache-2.0"
			(at 95.25 289.56 0)
			(effects
				(font
					(size 1.27 1.27)
					(thickness 0.15)
				)
				(justify left bottom)
				(hide yes)
			)
		)
		(pin "1"
		)
		(pin "2"
		)
		(pin "3"
		)
		(instances
			(project "cm4-baseboard"
				(path ""
					(reference "S203")
					(unit 1)
				)
			)
		)
	)
	(symbol
		(lib_id "antmicropower:GND")
		(at 123.19 209.55 0)
		(unit 1)
		(exclude_from_sim no)
		(in_bom yes)
		(on_board yes)
		(dnp no)
		(property "Reference" "#PWR0214"
			(at 123.19 215.9 0)
			(effects
				(font
					(size 1.27 1.27)
				)
				(justify left bottom)
				(hide yes)
			)
		)
		(property "Value" "GND"
			(at 123.19 213.36 0)
			(effects
				(font
					(size 1.27 1.27)
				)
			)
		)
		(property "Footprint" ""
			(at 132.08 217.17 0)
			(effects
				(font
					(size 1.27 1.27)
					(thickness 0.15)
				)
				(justify left bottom)
				(hide yes)
			)
		)
		(property "Datasheet" ""
			(at 132.08 222.25 0)
			(effects
				(font
					(size 1.27 1.27)
					(thickness 0.15)
				)
				(justify left bottom)
				(hide yes)
			)
		)
		(property "Description" ""
			(at 123.19 209.55 0)
			(effects
				(font
					(size 1.27 1.27)
				)
				(hide yes)
			)
		)
		(property "Author" "Antmicro"
			(at 132.08 217.17 0)
			(effects
				(font
					(size 1.27 1.27)
					(thickness 0.15)
				)
				(justify left bottom)
				(hide yes)
			)
		)
		(property "License" "Apache-2.0"
			(at 132.08 219.71 0)
			(effects
				(font
					(size 1.27 1.27)
					(thickness 0.15)
				)
				(justify left bottom)
				(hide yes)
			)
		)
		(pin "1"
		)
		(instances
			(project "cm4-baseboard"
				(path ""
					(reference "#PWR0214")
					(unit 1)
				)
			)
		)
	)
	(symbol
		(lib_id "antmicropower:+3V3")
		(at 306.07 21.59 0)
		(unit 1)
		(exclude_from_sim no)
		(in_bom yes)
		(on_board yes)
		(dnp no)
		(property "Reference" "#PWR0263"
			(at 321.31 21.59 0)
			(effects
				(font
					(size 1.27 1.27)
					(thickness 0.15)
				)
				(justify left bottom)
				(hide yes)
			)
		)
		(property "Value" "+3V3"
			(at 306.07 17.78 0)
			(effects
				(font
					(size 1.27 1.27)
					(thickness 0.15)
				)
			)
		)
		(property "Footprint" ""
			(at 321.31 29.21 0)
			(effects
				(font
					(size 1.27 1.27)
					(thickness 0.15)
				)
				(justify left bottom)
				(hide yes)
			)
		)
		(property "Datasheet" ""
			(at 321.31 31.75 0)
			(effects
				(font
					(size 1.27 1.27)
					(thickness 0.15)
				)
				(justify left bottom)
				(hide yes)
			)
		)
		(property "Description" ""
			(at 306.07 21.59 0)
			(effects
				(font
					(size 1.27 1.27)
				)
				(hide yes)
			)
		)
		(property "Author" "Antmicro"
			(at 321.31 24.13 0)
			(effects
				(font
					(size 1.27 1.27)
					(thickness 0.15)
				)
				(justify left bottom)
				(hide yes)
			)
		)
		(property "License" "Apache-2.0"
			(at 321.31 26.67 0)
			(effects
				(font
					(size 1.27 1.27)
					(thickness 0.15)
				)
				(justify left bottom)
				(hide yes)
			)
		)
		(pin "1"
		)
		(instances
			(project "cm4-baseboard"
				(path ""
					(reference "#PWR0263")
					(unit 1)
				)
			)
		)
	)
	(symbol
		(lib_id "antmicropower:+3V3")
		(at 266.7 189.23 0)
		(unit 1)
		(exclude_from_sim no)
		(in_bom yes)
		(on_board yes)
		(dnp no)
		(fields_autoplaced yes)
		(property "Reference" "#PWR0243"
			(at 281.94 191.77 0)
			(effects
				(font
					(size 1.27 1.27)
					(thickness 0.15)
				)
				(justify left bottom)
				(hide yes)
			)
		)
		(property "Value" "+3V3"
			(at 266.065 185.42 0)
			(effects
				(font
					(size 1.27 1.27)
					(thickness 0.15)
				)
			)
		)
		(property "Footprint" ""
			(at 281.94 196.85 0)
			(effects
				(font
					(size 1.27 1.27)
					(thickness 0.15)
				)
				(justify left bottom)
				(hide yes)
			)
		)
		(property "Datasheet" ""
			(at 281.94 199.39 0)
			(effects
				(font
					(size 1.27 1.27)
					(thickness 0.15)
				)
				(justify left bottom)
				(hide yes)
			)
		)
		(property "Description" ""
			(at 266.7 189.23 0)
			(effects
				(font
					(size 1.27 1.27)
				)
				(hide yes)
			)
		)
		(property "Author" "Antmicro"
			(at 281.94 196.85 0)
			(effects
				(font
					(size 1.27 1.27)
					(thickness 0.15)
				)
				(justify left bottom)
				(hide yes)
			)
		)
		(property "License" "Apache-2.0"
			(at 281.94 199.39 0)
			(effects
				(font
					(size 1.27 1.27)
					(thickness 0.15)
				)
				(justify left bottom)
				(hide yes)
			)
		)
		(pin "1"
		)
		(instances
			(project "cm4-baseboard"
				(path ""
					(reference "#PWR0243")
					(unit 1)
				)
			)
		)
	)
	(symbol
		(lib_id "antmicroTransistorsFETsMOSFETsSingle:PJE138K")
		(at 351.79 237.49 0)
		(unit 1)
		(exclude_from_sim no)
		(in_bom yes)
		(on_board yes)
		(dnp no)
		(fields_autoplaced yes)
		(property "Reference" "Q211"
			(at 363.22 233.6799 0)
			(effects
				(font
					(size 1.27 1.27)
					(thickness 0.15)
				)
				(justify left)
			)
		)
		(property "Value" "PJE138K"
			(at 363.22 236.2199 0)
			(effects
				(font
					(size 1.27 1.27)
					(thickness 0.15)
				)
				(justify left)
			)
		)
		(property "Footprint" "antmicro-footprints:SOT-523"
			(at 374.65 248.92 0)
			(effects
				(font
					(size 1.27 1.27)
					(thickness 0.15)
				)
				(justify left bottom)
				(hide yes)
			)
		)
		(property "Datasheet" "https://www.mouser.com/datasheet/2/1057/PJE138K-1876698.pdf"
			(at 374.65 251.46 0)
			(effects
				(font
					(size 1.27 1.27)
					(thickness 0.15)
				)
				(justify left bottom)
				(hide yes)
			)
		)
		(property "Description" ""
			(at 351.79 237.49 0)
			(effects
				(font
					(size 1.27 1.27)
				)
				(hide yes)
			)
		)
		(property "MPN" "PJE138K_R1_00001"
			(at 374.65 254 0)
			(effects
				(font
					(size 1.27 1.27)
					(thickness 0.15)
				)
				(justify left bottom)
				(hide yes)
			)
		)
		(property "Manufacturer" "PANJIT"
			(at 374.65 256.54 0)
			(effects
				(font
					(size 1.27 1.27)
					(thickness 0.15)
				)
				(justify left bottom)
				(hide yes)
			)
		)
		(property "Author" "Antmicro"
			(at 374.65 259.08 0)
			(effects
				(font
					(size 1.27 1.27)
					(thickness 0.15)
				)
				(justify left bottom)
				(hide yes)
			)
		)
		(property "License" "Apache-2.0"
			(at 374.65 261.62 0)
			(effects
				(font
					(size 1.27 1.27)
					(thickness 0.15)
				)
				(justify left bottom)
				(hide yes)
			)
		)
		(pin "1"
		)
		(pin "2"
		)
		(pin "3"
		)
		(instances
			(project "cm4-baseboard"
				(path ""
					(reference "Q211")
					(unit 1)
				)
			)
		)
	)
	(symbol
		(lib_id "antmicropower:GND")
		(at 266.7 196.85 0)
		(unit 1)
		(exclude_from_sim no)
		(in_bom yes)
		(on_board yes)
		(dnp no)
		(property "Reference" "#PWR0244"
			(at 275.59 199.39 0)
			(effects
				(font
					(size 1.27 1.27)
					(thickness 0.15)
				)
				(justify left bottom)
				(hide yes)
			)
		)
		(property "Value" "GND"
			(at 266.7 201.295 0)
			(effects
				(font
					(size 1.27 1.27)
					(thickness 0.15)
				)
			)
		)
		(property "Footprint" ""
			(at 275.59 204.47 0)
			(effects
				(font
					(size 1.27 1.27)
					(thickness 0.15)
				)
				(justify left bottom)
				(hide yes)
			)
		)
		(property "Datasheet" ""
			(at 275.59 209.55 0)
			(effects
				(font
					(size 1.27 1.27)
					(thickness 0.15)
				)
				(justify left bottom)
				(hide yes)
			)
		)
		(property "Description" ""
			(at 266.7 196.85 0)
			(effects
				(font
					(size 1.27 1.27)
				)
				(hide yes)
			)
		)
		(property "Author" "Antmicro"
			(at 275.59 204.47 0)
			(effects
				(font
					(size 1.27 1.27)
					(thickness 0.15)
				)
				(justify left bottom)
				(hide yes)
			)
		)
		(property "License" "Apache-2.0"
			(at 275.59 207.01 0)
			(effects
				(font
					(size 1.27 1.27)
					(thickness 0.15)
				)
				(justify left bottom)
				(hide yes)
			)
		)
		(pin "1"
		)
		(instances
			(project "cm4-baseboard"
				(path ""
					(reference "#PWR0244")
					(unit 1)
				)
			)
		)
	)
	(symbol
		(lib_id "antmicroLogicTranslatorsLevelShifters:TXB0104_UQFN")
		(at 250.19 147.32 0)
		(unit 1)
		(exclude_from_sim no)
		(in_bom yes)
		(on_board yes)
		(dnp no)
		(fields_autoplaced yes)
		(property "Reference" "U201"
			(at 260.35 139.7 0)
			(effects
				(font
					(size 1.27 1.27)
					(thickness 0.15)
				)
			)
		)
		(property "Value" "TXB0104_UQFN"
			(at 260.35 142.24 0)
			(effects
				(font
					(size 1.27 1.27)
					(thickness 0.15)
				)
				(hide yes)
			)
		)
		(property "Footprint" "antmicro-footprints:UQFN-12_2x1.7mm_P0.4mm_Texas_RUT"
			(at 285.75 157.48 0)
			(effects
				(font
					(size 1.27 1.27)
					(thickness 0.15)
				)
				(justify left bottom)
				(hide yes)
			)
		)
		(property "Datasheet" "http://www.ti.com/lit/ds/symlink/txb0104.pdf"
			(at 285.75 160.02 0)
			(effects
				(font
					(size 1.27 1.27)
					(thickness 0.15)
				)
				(justify left bottom)
				(hide yes)
			)
		)
		(property "Description" ""
			(at 250.19 147.32 0)
			(effects
				(font
					(size 1.27 1.27)
				)
				(hide yes)
			)
		)
		(property "Manufacturer" "Texas Instruments"
			(at 285.75 162.56 0)
			(effects
				(font
					(size 1.27 1.27)
					(thickness 0.15)
				)
				(justify left bottom)
				(hide yes)
			)
		)
		(property "MPN" "TXB0104RUTR"
			(at 260.35 142.24 0)
			(effects
				(font
					(size 1.27 1.27)
					(thickness 0.15)
				)
			)
		)
		(property "Author" "Antmicro"
			(at 285.75 167.64 0)
			(effects
				(font
					(size 1.27 1.27)
					(thickness 0.15)
				)
				(justify left bottom)
				(hide yes)
			)
		)
		(property "License" "Apache-2.0"
			(at 285.75 170.18 0)
			(effects
				(font
					(size 1.27 1.27)
					(thickness 0.15)
				)
				(justify left bottom)
				(hide yes)
			)
		)
		(pin "1"
		)
		(pin "10"
		)
		(pin "11"
		)
		(pin "12"
		)
		(pin "2"
		)
		(pin "3"
		)
		(pin "4"
		)
		(pin "5"
		)
		(pin "6"
		)
		(pin "7"
		)
		(pin "8"
		)
		(pin "9"
		)
		(instances
			(project "cm4-baseboard"
				(path ""
					(reference "U201")
					(unit 1)
				)
			)
		)
	)
	(symbol
		(lib_id "antmicroCapacitors0402:C_100n_0402")
		(at 134.62 245.11 90)
		(unit 1)
		(exclude_from_sim no)
		(in_bom yes)
		(on_board yes)
		(dnp no)
		(fields_autoplaced yes)
		(property "Reference" "C202"
			(at 137.16 241.2935 90)
			(effects
				(font
					(size 1.27 1.27)
				)
				(justify right)
			)
		)
		(property "Value" "C_100n_0402"
			(at 138.43 245.11 0)
			(effects
				(font
					(size 1.27 1.27)
				)
				(justify left bottom)
				(hide yes)
			)
		)
		(property "Footprint" "antmicro-footprints:C_0402_1005Metric"
			(at 129.54 240.03 0)
			(effects
				(font
					(size 1.524 1.524)
				)
				(justify left bottom)
				(hide yes)
			)
		)
		(property "Datasheet" "https://www.murata.com/products/productdetail?partno=GRM155R61H104KE14%23"
			(at 134.62 245.11 0)
			(effects
				(font
					(size 1.27 1.27)
				)
				(justify left bottom)
				(hide yes)
			)
		)
		(property "Description" ""
			(at 134.62 245.11 0)
			(effects
				(font
					(size 1.27 1.27)
				)
				(hide yes)
			)
		)
		(property "Manufacturer" "Murata"
			(at 124.46 240.03 0)
			(effects
				(font
					(size 1.524 1.524)
				)
				(justify left bottom)
				(hide yes)
			)
		)
		(property "MPN" "GRM155R61H104KE14D"
			(at 127 240.03 0)
			(effects
				(font
					(size 1.524 1.524)
				)
				(justify left bottom)
				(hide yes)
			)
		)
		(property "Val" "100n"
			(at 137.16 243.8335 90)
			(effects
				(font
					(size 1.27 1.27)
				)
				(justify right)
			)
		)
		(property "License" "Apache-2.0"
			(at 157.48 224.79 0)
			(effects
				(font
					(size 1.27 1.27)
					(thickness 0.15)
				)
				(justify left bottom)
				(hide yes)
			)
		)
		(property "Author" "Antmicro"
			(at 160.02 224.79 0)
			(effects
				(font
					(size 1.27 1.27)
					(thickness 0.15)
				)
				(justify left bottom)
				(hide yes)
			)
		)
		(property "Voltage" "50V"
			(at 162.56 224.79 0)
			(effects
				(font
					(size 1.27 1.27)
				)
				(justify left bottom)
				(hide yes)
			)
		)
		(property "Dielectric" "X5R"
			(at 165.1 224.79 0)
			(effects
				(font
					(size 1.27 1.27)
				)
				(justify left bottom)
				(hide yes)
			)
		)
		(pin "1"
		)
		(pin "2"
		)
		(instances
			(project "cm4-baseboard"
				(path ""
					(reference "C202")
					(unit 1)
				)
			)
		)
	)
	(symbol
		(lib_id "antmicroResistors0402:R_1k_0402")
		(at 176.53 205.74 90)
		(unit 1)
		(exclude_from_sim no)
		(in_bom yes)
		(on_board yes)
		(dnp no)
		(property "Reference" "R224"
			(at 172.72 204.47 90)
			(effects
				(font
					(size 1.27 1.27)
					(thickness 0.15)
				)
			)
		)
		(property "Value" "R_1k_0402"
			(at 189.23 185.42 0)
			(effects
				(font
					(size 1.27 1.27)
					(thickness 0.15)
				)
				(justify left bottom)
				(hide yes)
			)
		)
		(property "Footprint" "antmicro-footprints:R_0402_1005Metric"
			(at 191.77 185.42 0)
			(effects
				(font
					(size 1.27 1.27)
					(thickness 0.15)
				)
				(justify left bottom)
				(hide yes)
			)
		)
		(property "Datasheet" "https://www.bourns.com/docs/product-datasheets/cr.pdf"
			(at 194.31 185.42 0)
			(effects
				(font
					(size 1.27 1.27)
					(thickness 0.15)
				)
				(justify left bottom)
				(hide yes)
			)
		)
		(property "Description" ""
			(at 176.53 205.74 0)
			(effects
				(font
					(size 1.27 1.27)
				)
				(hide yes)
			)
		)
		(property "MPN" "CR0402-FX-1001GLF"
			(at 196.85 185.42 0)
			(effects
				(font
					(size 1.27 1.27)
					(thickness 0.15)
				)
				(justify left bottom)
				(hide yes)
			)
		)
		(property "Manufacturer" "Bourns"
			(at 199.39 185.42 0)
			(effects
				(font
					(size 1.27 1.27)
					(thickness 0.15)
				)
				(justify left bottom)
				(hide yes)
			)
		)
		(property "License" "Apache-2.0"
			(at 201.93 185.42 0)
			(effects
				(font
					(size 1.27 1.27)
					(thickness 0.15)
				)
				(justify left bottom)
				(hide yes)
			)
		)
		(property "Author" "Antmicro"
			(at 204.47 185.42 0)
			(effects
				(font
					(size 1.27 1.27)
					(thickness 0.15)
				)
				(justify left bottom)
				(hide yes)
			)
		)
		(property "Val" "1k"
			(at 173.99 201.93 90)
			(effects
				(font
					(size 1.27 1.27)
					(thickness 0.15)
				)
			)
		)
		(property "Tolerance" "1%"
			(at 186.69 185.42 0)
			(effects
				(font
					(size 1.27 1.27)
				)
				(justify left bottom)
				(hide yes)
			)
		)
		(pin "1"
		)
		(pin "2"
		)
		(instances
			(project "cm4-baseboard"
				(path ""
					(reference "R224")
					(unit 1)
				)
			)
		)
	)
	(symbol
		(lib_id "antmicroTestPoints:TP_0.75mm_SMD")
		(at 43.18 158.75 180)
		(unit 1)
		(exclude_from_sim no)
		(in_bom no)
		(on_board yes)
		(dnp no)
		(property "Reference" "TP202"
			(at 35.56 158.75 0)
			(effects
				(font
					(size 1.27 1.27)
					(thickness 0.15)
				)
			)
		)
		(property "Value" "TP_0.75mm_SMD"
			(at 27.94 151.13 0)
			(effects
				(font
					(size 1.27 1.27)
					(thickness 0.15)
				)
				(justify left bottom)
				(hide yes)
			)
		)
		(property "Footprint" "antmicro-footprints:TP_SMD_0.75mm"
			(at 32.385 152.4 0)
			(effects
				(font
					(size 1.27 1.27)
					(thickness 0.15)
				)
				(justify left bottom)
				(hide yes)
			)
		)
		(property "Datasheet" ""
			(at 25.4 146.05 0)
			(effects
				(font
					(size 1.27 1.27)
					(thickness 0.15)
				)
				(justify left bottom)
				(hide yes)
			)
		)
		(property "Description" ""
			(at 43.18 158.75 0)
			(effects
				(font
					(size 1.27 1.27)
				)
				(hide yes)
			)
		)
		(property "Author" "Antmicro"
			(at 32.385 149.86 0)
			(effects
				(font
					(size 1.27 1.27)
					(thickness 0.15)
				)
				(justify left bottom)
				(hide yes)
			)
		)
		(property "License" "Apache-2.0"
			(at 32.385 147.32 0)
			(effects
				(font
					(size 1.27 1.27)
					(thickness 0.15)
				)
				(justify left bottom)
				(hide yes)
			)
		)
		(property "MPN" ""
			(at 32.385 147.32 0)
			(effects
				(font
					(size 1.27 1.27)
					(thickness 0.15)
				)
				(justify left bottom)
				(hide yes)
			)
		)
		(property "Manufacturer" ""
			(at 32.385 152.4 0)
			(effects
				(font
					(size 1.27 1.27)
					(thickness 0.15)
				)
				(justify left bottom)
				(hide yes)
			)
		)
		(pin "1"
		)
		(instances
			(project "cm4-baseboard"
				(path ""
					(reference "TP202")
					(unit 1)
				)
			)
		)
	)
	(symbol
		(lib_id "antmicropower:GND")
		(at 44.45 259.08 0)
		(unit 1)
		(exclude_from_sim no)
		(in_bom yes)
		(on_board yes)
		(dnp no)
		(property "Reference" "#PWR0205"
			(at 53.34 261.62 0)
			(effects
				(font
					(size 1.27 1.27)
					(thickness 0.15)
				)
				(justify left bottom)
				(hide yes)
			)
		)
		(property "Value" "GND"
			(at 44.45 262.89 0)
			(effects
				(font
					(size 1.27 1.27)
					(thickness 0.15)
				)
			)
		)
		(property "Footprint" ""
			(at 53.34 266.7 0)
			(effects
				(font
					(size 1.27 1.27)
					(thickness 0.15)
				)
				(justify left bottom)
				(hide yes)
			)
		)
		(property "Datasheet" ""
			(at 53.34 271.78 0)
			(effects
				(font
					(size 1.27 1.27)
					(thickness 0.15)
				)
				(justify left bottom)
				(hide yes)
			)
		)
		(property "Description" ""
			(at 44.45 259.08 0)
			(effects
				(font
					(size 1.27 1.27)
				)
				(hide yes)
			)
		)
		(property "Author" "Antmicro"
			(at 53.34 266.7 0)
			(effects
				(font
					(size 1.27 1.27)
					(thickness 0.15)
				)
				(justify left bottom)
				(hide yes)
			)
		)
		(property "License" "Apache-2.0"
			(at 53.34 269.24 0)
			(effects
				(font
					(size 1.27 1.27)
					(thickness 0.15)
				)
				(justify left bottom)
				(hide yes)
			)
		)
		(pin "1"
		)
		(instances
			(project "cm4-baseboard"
				(path ""
					(reference "#PWR0205")
					(unit 1)
				)
			)
		)
	)
	(symbol
		(lib_id "antmicroResistors0402:R_0R_0402")
		(at 81.28 168.91 0)
		(unit 1)
		(exclude_from_sim no)
		(in_bom no)
		(on_board yes)
		(dnp yes)
		(property "Reference" "R208"
			(at 83.82 163.83 0)
			(effects
				(font
					(size 1.27 1.27)
				)
			)
		)
		(property "Value" "R_0R_0402"
			(at 81.28 172.72 0)
			(effects
				(font
					(size 1.27 1.27)
				)
				(justify left bottom)
				(hide yes)
			)
		)
		(property "Footprint" "antmicro-footprints:R_0402_1005Metric"
			(at 86.36 163.83 0)
			(effects
				(font
					(size 1.524 1.524)
				)
				(justify left bottom)
				(hide yes)
			)
		)
		(property "Datasheet" "https://industrial.panasonic.com/cdbs/www-data/pdf/RDA0000/AOA0000C301.pdf"
			(at 81.28 168.91 0)
			(effects
				(font
					(size 1.27 1.27)
				)
				(justify left bottom)
				(hide yes)
			)
		)
		(property "Description" ""
			(at 81.28 168.91 0)
			(effects
				(font
					(size 1.27 1.27)
				)
				(hide yes)
			)
		)
		(property "Manufacturer" "Panasonic"
			(at 86.36 158.75 0)
			(effects
				(font
					(size 1.524 1.524)
				)
				(justify left bottom)
				(hide yes)
			)
		)
		(property "MPN" "ERJ2GE0R00X"
			(at 86.36 161.29 0)
			(effects
				(font
					(size 1.524 1.524)
				)
				(justify left bottom)
				(hide yes)
			)
		)
		(property "Val" "0R"
			(at 83.82 166.37 0)
			(effects
				(font
					(size 1.27 1.27)
				)
			)
		)
		(property "License" "Apache-2.0"
			(at 101.6 194.31 0)
			(effects
				(font
					(size 1.27 1.27)
					(thickness 0.15)
				)
				(justify left bottom)
				(hide yes)
			)
		)
		(property "Author" "Antmicro"
			(at 101.6 196.85 0)
			(effects
				(font
					(size 1.27 1.27)
					(thickness 0.15)
				)
				(justify left bottom)
				(hide yes)
			)
		)
		(property "Tolerance" "~"
			(at 101.6 179.07 0)
			(effects
				(font
					(size 1.27 1.27)
				)
				(justify left bottom)
				(hide yes)
			)
		)
		(property "Current" "1A"
			(at 83.82 167.005 0)
			(effects
				(font
					(size 1.27 1.27)
					(thickness 0.15)
				)
				(hide yes)
			)
		)
		(pin "1"
		)
		(pin "2"
		)
		(instances
			(project "cm4-baseboard"
				(path ""
					(reference "R208")
					(unit 1)
				)
			)
		)
	)
	(symbol
		(lib_id "antmicroLEDIndicationDiscrete:LED_G_0603_KP-1608CGCK")
		(at 227.33 212.09 270)
		(mirror x)
		(unit 1)
		(exclude_from_sim no)
		(in_bom yes)
		(on_board yes)
		(dnp no)
		(property "Reference" "D202"
			(at 223.52 208.28 90)
			(effects
				(font
					(size 1.27 1.27)
					(thickness 0.15)
				)
			)
		)
		(property "Value" "LED_G_0603_KP-1608CGCK"
			(at 219.71 189.23 0)
			(effects
				(font
					(size 1.27 1.27)
					(thickness 0.15)
				)
				(justify left bottom)
				(hide yes)
			)
		)
		(property "Footprint" "antmicro-footprints:LED_0603_1608Metric_G"
			(at 217.17 189.23 0)
			(effects
				(font
					(size 1.27 1.27)
					(thickness 0.15)
				)
				(justify left bottom)
				(hide yes)
			)
		)
		(property "Datasheet" "http://www.kingbright.com/attachments/file/psearch//000/00/00/KP-1608CGCK(Ver.23B).pdf"
			(at 214.63 189.23 0)
			(effects
				(font
					(size 1.27 1.27)
					(thickness 0.15)
				)
				(justify left bottom)
				(hide yes)
			)
		)
		(property "Description" ""
			(at 227.33 212.09 0)
			(effects
				(font
					(size 1.27 1.27)
				)
				(hide yes)
			)
		)
		(property "MPN" "KP-1608CGCK"
			(at 212.09 189.23 0)
			(effects
				(font
					(size 1.27 1.27)
					(thickness 0.15)
				)
				(justify left bottom)
				(hide yes)
			)
		)
		(property "Manufacturer" "Kingbright"
			(at 209.55 189.23 0)
			(effects
				(font
					(size 1.27 1.27)
					(thickness 0.15)
				)
				(justify left bottom)
				(hide yes)
			)
		)
		(property "Color" "Green"
			(at 223.52 210.82 90)
			(effects
				(font
					(size 1.27 1.27)
				)
			)
		)
		(property "Author" "Antmicro"
			(at 207.01 189.23 0)
			(effects
				(font
					(size 1.27 1.27)
					(thickness 0.15)
				)
				(justify left bottom)
				(hide yes)
			)
		)
		(property "License" "Apache-2.0"
			(at 204.47 189.23 0)
			(effects
				(font
					(size 1.27 1.27)
					(thickness 0.15)
				)
				(justify left bottom)
				(hide yes)
			)
		)
		(pin "2"
		)
		(pin "1"
		)
		(instances
			(project "cm4-baseboard"
				(path ""
					(reference "D202")
					(unit 1)
				)
			)
		)
	)
	(symbol
		(lib_id "antmicropower:+3V3")
		(at 134.62 185.42 0)
		(unit 1)
		(exclude_from_sim no)
		(in_bom yes)
		(on_board yes)
		(dnp no)
		(property "Reference" "#PWR0216"
			(at 149.86 185.42 0)
			(effects
				(font
					(size 1.27 1.27)
					(thickness 0.15)
				)
				(justify left bottom)
				(hide yes)
			)
		)
		(property "Value" "+3V3"
			(at 134.62 181.61 0)
			(effects
				(font
					(size 1.27 1.27)
					(thickness 0.15)
				)
			)
		)
		(property "Footprint" ""
			(at 149.86 193.04 0)
			(effects
				(font
					(size 1.27 1.27)
					(thickness 0.15)
				)
				(justify left bottom)
				(hide yes)
			)
		)
		(property "Datasheet" ""
			(at 149.86 195.58 0)
			(effects
				(font
					(size 1.27 1.27)
					(thickness 0.15)
				)
				(justify left bottom)
				(hide yes)
			)
		)
		(property "Description" ""
			(at 134.62 185.42 0)
			(effects
				(font
					(size 1.27 1.27)
				)
				(hide yes)
			)
		)
		(property "Author" "Antmicro"
			(at 149.86 187.96 0)
			(effects
				(font
					(size 1.27 1.27)
					(thickness 0.15)
				)
				(justify left bottom)
				(hide yes)
			)
		)
		(property "License" "Apache-2.0"
			(at 149.86 190.5 0)
			(effects
				(font
					(size 1.27 1.27)
					(thickness 0.15)
				)
				(justify left bottom)
				(hide yes)
			)
		)
		(pin "1"
		)
		(instances
			(project "cm4-baseboard"
				(path ""
					(reference "#PWR0216")
					(unit 1)
				)
			)
		)
	)
	(symbol
		(lib_id "antmicropower:+5V")
		(at 196.85 193.04 0)
		(unit 1)
		(exclude_from_sim no)
		(in_bom yes)
		(on_board yes)
		(dnp no)
		(fields_autoplaced yes)
		(property "Reference" "#PWR030"
			(at 212.09 195.58 0)
			(effects
				(font
					(size 1.27 1.27)
					(thickness 0.15)
				)
				(justify left bottom)
				(hide yes)
			)
		)
		(property "Value" "+5V"
			(at 196.85 187.96 0)
			(effects
				(font
					(size 1.27 1.27)
					(thickness 0.15)
				)
			)
		)
		(property "Footprint" ""
			(at 212.09 200.66 0)
			(effects
				(font
					(size 1.27 1.27)
					(thickness 0.15)
				)
				(justify left bottom)
				(hide yes)
			)
		)
		(property "Datasheet" ""
			(at 212.09 203.2 0)
			(effects
				(font
					(size 1.27 1.27)
					(thickness 0.15)
				)
				(justify left bottom)
				(hide yes)
			)
		)
		(property "Description" ""
			(at 196.85 193.04 0)
			(effects
				(font
					(size 1.27 1.27)
				)
				(hide yes)
			)
		)
		(property "Author" "Antmicro"
			(at 212.09 200.66 0)
			(effects
				(font
					(size 1.27 1.27)
					(thickness 0.15)
				)
				(justify left bottom)
				(hide yes)
			)
		)
		(property "License" "Apache-2.0"
			(at 212.09 203.2 0)
			(effects
				(font
					(size 1.27 1.27)
					(thickness 0.15)
				)
				(justify left bottom)
				(hide yes)
			)
		)
		(pin "1"
		)
		(instances
			(project "cm4-baseboard"
				(path ""
					(reference "#PWR030")
					(unit 1)
				)
			)
		)
	)
	(symbol
		(lib_id "antmicroTransistorsFETsMOSFETsSingle:SSM3J332R")
		(at 220.98 195.58 0)
		(mirror x)
		(unit 1)
		(exclude_from_sim no)
		(in_bom yes)
		(on_board yes)
		(dnp no)
		(property "Reference" "Q206"
			(at 224.79 201.295 0)
			(effects
				(font
					(size 1.27 1.27)
					(thickness 0.15)
				)
				(justify right)
			)
		)
		(property "Value" "SSM3J332R"
			(at 224.79 203.835 0)
			(effects
				(font
					(size 1.27 1.27)
					(thickness 0.15)
				)
				(justify right)
			)
		)
		(property "Footprint" "antmicro-footprints:SOT-23-3"
			(at 243.84 184.15 0)
			(effects
				(font
					(size 1.27 1.27)
					(thickness 0.15)
				)
				(justify left bottom)
				(hide yes)
			)
		)
		(property "Datasheet" "https://www.mouser.com/datasheet/2/408/SSM3J332R_datasheet_en_20181015-1150575.pdf"
			(at 243.84 181.61 0)
			(effects
				(font
					(size 1.27 1.27)
					(thickness 0.15)
				)
				(justify left bottom)
				(hide yes)
			)
		)
		(property "Description" ""
			(at 220.98 195.58 0)
			(effects
				(font
					(size 1.27 1.27)
				)
				(hide yes)
			)
		)
		(property "MPN" "SSM3J332R,LF"
			(at 243.84 179.07 0)
			(effects
				(font
					(size 1.27 1.27)
					(thickness 0.15)
				)
				(justify left bottom)
				(hide yes)
			)
		)
		(property "Manufacturer" "Toshiba"
			(at 243.84 176.53 0)
			(effects
				(font
					(size 1.27 1.27)
					(thickness 0.15)
				)
				(justify left bottom)
				(hide yes)
			)
		)
		(property "Author" "Antmicro"
			(at 243.84 173.99 0)
			(effects
				(font
					(size 1.27 1.27)
					(thickness 0.15)
				)
				(justify left bottom)
				(hide yes)
			)
		)
		(property "License" "Apache-2.0"
			(at 243.84 171.45 0)
			(effects
				(font
					(size 1.27 1.27)
					(thickness 0.15)
				)
				(justify left bottom)
				(hide yes)
			)
		)
		(pin "1"
		)
		(pin "2"
		)
		(pin "3"
		)
		(instances
			(project "cm4-baseboard"
				(path ""
					(reference "Q206")
					(unit 1)
				)
			)
		)
	)
	(symbol
		(lib_id "antmicropower:GND")
		(at 271.78 175.26 0)
		(unit 1)
		(exclude_from_sim no)
		(in_bom yes)
		(on_board yes)
		(dnp no)
		(property "Reference" "#PWR0246"
			(at 280.67 177.8 0)
			(effects
				(font
					(size 1.27 1.27)
					(thickness 0.15)
				)
				(justify left bottom)
				(hide yes)
			)
		)
		(property "Value" "GND"
			(at 271.78 179.705 0)
			(effects
				(font
					(size 1.27 1.27)
					(thickness 0.15)
				)
			)
		)
		(property "Footprint" ""
			(at 280.67 182.88 0)
			(effects
				(font
					(size 1.27 1.27)
					(thickness 0.15)
				)
				(justify left bottom)
				(hide yes)
			)
		)
		(property "Datasheet" ""
			(at 280.67 187.96 0)
			(effects
				(font
					(size 1.27 1.27)
					(thickness 0.15)
				)
				(justify left bottom)
				(hide yes)
			)
		)
		(property "Description" ""
			(at 271.78 175.26 0)
			(effects
				(font
					(size 1.27 1.27)
				)
				(hide yes)
			)
		)
		(property "Author" "Antmicro"
			(at 280.67 182.88 0)
			(effects
				(font
					(size 1.27 1.27)
					(thickness 0.15)
				)
				(justify left bottom)
				(hide yes)
			)
		)
		(property "License" "Apache-2.0"
			(at 280.67 185.42 0)
			(effects
				(font
					(size 1.27 1.27)
					(thickness 0.15)
				)
				(justify left bottom)
				(hide yes)
			)
		)
		(pin "1"
		)
		(instances
			(project "cm4-baseboard"
				(path ""
					(reference "#PWR0246")
					(unit 1)
				)
			)
		)
	)
	(symbol
		(lib_id "antmicroCapacitors0402:C_100n_0402")
		(at 255.27 127 90)
		(unit 1)
		(exclude_from_sim no)
		(in_bom yes)
		(on_board yes)
		(dnp no)
		(fields_autoplaced yes)
		(property "Reference" "C204"
			(at 256.54 121.92 90)
			(effects
				(font
					(size 1.27 1.27)
					(thickness 0.15)
				)
				(justify right)
			)
		)
		(property "Value" "C_100n_0402"
			(at 265.43 106.68 0)
			(effects
				(font
					(size 1.27 1.27)
					(thickness 0.15)
				)
				(justify left bottom)
				(hide yes)
			)
		)
		(property "Footprint" "antmicro-footprints:C_0402_1005Metric"
			(at 267.97 106.68 0)
			(effects
				(font
					(size 1.27 1.27)
					(thickness 0.15)
				)
				(justify left bottom)
				(hide yes)
			)
		)
		(property "Datasheet" "https://www.murata.com/products/productdetail?partno=GRM155R61H104KE14%23"
			(at 270.51 106.68 0)
			(effects
				(font
					(size 1.27 1.27)
					(thickness 0.15)
				)
				(justify left bottom)
				(hide yes)
			)
		)
		(property "Description" ""
			(at 255.27 127 0)
			(effects
				(font
					(size 1.27 1.27)
				)
				(hide yes)
			)
		)
		(property "MPN" "GRM155R61H104KE14D"
			(at 273.05 106.68 0)
			(effects
				(font
					(size 1.27 1.27)
					(thickness 0.15)
				)
				(justify left bottom)
				(hide yes)
			)
		)
		(property "Manufacturer" "Murata"
			(at 275.59 106.68 0)
			(effects
				(font
					(size 1.27 1.27)
					(thickness 0.15)
				)
				(justify left bottom)
				(hide yes)
			)
		)
		(property "License" "Apache-2.0"
			(at 278.13 106.68 0)
			(effects
				(font
					(size 1.27 1.27)
					(thickness 0.15)
				)
				(justify left bottom)
				(hide yes)
			)
		)
		(property "Author" "Antmicro"
			(at 280.67 106.68 0)
			(effects
				(font
					(size 1.27 1.27)
					(thickness 0.15)
				)
				(justify left bottom)
				(hide yes)
			)
		)
		(property "Val" "100n"
			(at 256.54 127 90)
			(effects
				(font
					(size 1.27 1.27)
					(thickness 0.15)
				)
				(justify right)
			)
		)
		(property "Voltage" "50V"
			(at 283.21 106.68 0)
			(effects
				(font
					(size 1.27 1.27)
				)
				(justify left bottom)
				(hide yes)
			)
		)
		(property "Dielectric" "X5R"
			(at 285.75 106.68 0)
			(effects
				(font
					(size 1.27 1.27)
				)
				(justify left bottom)
				(hide yes)
			)
		)
		(pin "1"
		)
		(pin "2"
		)
		(instances
			(project "cm4-baseboard"
				(path ""
					(reference "C204")
					(unit 1)
				)
			)
		)
	)
	(symbol
		(lib_id "antmicroCapacitors0402:C_100n_0402")
		(at 134.62 208.28 90)
		(unit 1)
		(exclude_from_sim no)
		(in_bom yes)
		(on_board yes)
		(dnp no)
		(fields_autoplaced yes)
		(property "Reference" "C201"
			(at 137.16 204.4635 90)
			(effects
				(font
					(size 1.27 1.27)
				)
				(justify right)
			)
		)
		(property "Value" "C_100n_0402"
			(at 138.43 208.28 0)
			(effects
				(font
					(size 1.27 1.27)
				)
				(justify left bottom)
				(hide yes)
			)
		)
		(property "Footprint" "antmicro-footprints:C_0402_1005Metric"
			(at 129.54 203.2 0)
			(effects
				(font
					(size 1.524 1.524)
				)
				(justify left bottom)
				(hide yes)
			)
		)
		(property "Datasheet" "https://www.murata.com/products/productdetail?partno=GRM155R61H104KE14%23"
			(at 134.62 208.28 0)
			(effects
				(font
					(size 1.27 1.27)
				)
				(justify left bottom)
				(hide yes)
			)
		)
		(property "Description" ""
			(at 134.62 208.28 0)
			(effects
				(font
					(size 1.27 1.27)
				)
				(hide yes)
			)
		)
		(property "Manufacturer" "Murata"
			(at 124.46 203.2 0)
			(effects
				(font
					(size 1.524 1.524)
				)
				(justify left bottom)
				(hide yes)
			)
		)
		(property "MPN" "GRM155R61H104KE14D"
			(at 127 203.2 0)
			(effects
				(font
					(size 1.524 1.524)
				)
				(justify left bottom)
				(hide yes)
			)
		)
		(property "Val" "100n"
			(at 137.16 207.0035 90)
			(effects
				(font
					(size 1.27 1.27)
				)
				(justify right)
			)
		)
		(property "License" "Apache-2.0"
			(at 157.48 187.96 0)
			(effects
				(font
					(size 1.27 1.27)
					(thickness 0.15)
				)
				(justify left bottom)
				(hide yes)
			)
		)
		(property "Author" "Antmicro"
			(at 160.02 187.96 0)
			(effects
				(font
					(size 1.27 1.27)
					(thickness 0.15)
				)
				(justify left bottom)
				(hide yes)
			)
		)
		(property "Voltage" "50V"
			(at 162.56 187.96 0)
			(effects
				(font
					(size 1.27 1.27)
				)
				(justify left bottom)
				(hide yes)
			)
		)
		(property "Dielectric" "X5R"
			(at 165.1 187.96 0)
			(effects
				(font
					(size 1.27 1.27)
				)
				(justify left bottom)
				(hide yes)
			)
		)
		(pin "1"
		)
		(pin "2"
		)
		(instances
			(project "cm4-baseboard"
				(path ""
					(reference "C201")
					(unit 1)
				)
			)
		)
	)
	(symbol
		(lib_id "antmicroResistors0402:R_0R_0402")
		(at 156.21 100.33 0)
		(unit 1)
		(exclude_from_sim no)
		(in_bom yes)
		(on_board yes)
		(dnp no)
		(property "Reference" "R219"
			(at 153.67 99.06 0)
			(effects
				(font
					(size 1.27 1.27)
				)
			)
		)
		(property "Value" "R_0R_0402"
			(at 156.21 104.14 0)
			(effects
				(font
					(size 1.27 1.27)
				)
				(justify left bottom)
				(hide yes)
			)
		)
		(property "Footprint" "antmicro-footprints:R_0402_1005Metric"
			(at 161.29 95.25 0)
			(effects
				(font
					(size 1.524 1.524)
				)
				(justify left bottom)
				(hide yes)
			)
		)
		(property "Datasheet" "https://industrial.panasonic.com/cdbs/www-data/pdf/RDA0000/AOA0000C301.pdf"
			(at 156.21 100.33 0)
			(effects
				(font
					(size 1.27 1.27)
				)
				(justify left bottom)
				(hide yes)
			)
		)
		(property "Description" ""
			(at 156.21 100.33 0)
			(effects
				(font
					(size 1.27 1.27)
				)
				(hide yes)
			)
		)
		(property "Manufacturer" "Panasonic"
			(at 161.29 90.17 0)
			(effects
				(font
					(size 1.524 1.524)
				)
				(justify left bottom)
				(hide yes)
			)
		)
		(property "MPN" "ERJ2GE0R00X"
			(at 161.29 92.71 0)
			(effects
				(font
					(size 1.524 1.524)
				)
				(justify left bottom)
				(hide yes)
			)
		)
		(property "Val" "0R"
			(at 162.56 99.06 0)
			(effects
				(font
					(size 1.27 1.27)
				)
			)
		)
		(property "License" "Apache-2.0"
			(at 176.53 125.73 0)
			(effects
				(font
					(size 1.27 1.27)
					(thickness 0.15)
				)
				(justify left bottom)
				(hide yes)
			)
		)
		(property "Author" "Antmicro"
			(at 176.53 128.27 0)
			(effects
				(font
					(size 1.27 1.27)
					(thickness 0.15)
				)
				(justify left bottom)
				(hide yes)
			)
		)
		(property "Tolerance" "~"
			(at 176.53 110.49 0)
			(effects
				(font
					(size 1.27 1.27)
				)
				(justify left bottom)
				(hide yes)
			)
		)
		(property "Current" "1A"
			(at 158.75 98.425 0)
			(effects
				(font
					(size 1.27 1.27)
					(thickness 0.15)
				)
				(hide yes)
			)
		)
		(pin "1"
		)
		(pin "2"
		)
		(instances
			(project "cm4-baseboard"
				(path ""
					(reference "R219")
					(unit 1)
				)
			)
		)
	)
	(symbol
		(lib_id "antmicroResistors0402:R_0R_0402")
		(at 40.64 63.5 90)
		(unit 1)
		(exclude_from_sim no)
		(in_bom no)
		(on_board yes)
		(dnp yes)
		(property "Reference" "R205"
			(at 38.1 58.4199 90)
			(effects
				(font
					(size 1.27 1.27)
					(thickness 0.15)
				)
				(justify left)
			)
		)
		(property "Value" "R_0R_0402"
			(at 53.34 43.18 0)
			(effects
				(font
					(size 1.27 1.27)
					(thickness 0.15)
				)
				(justify left bottom)
				(hide yes)
			)
		)
		(property "Footprint" "antmicro-footprints:R_0402_1005Metric"
			(at 55.88 43.18 0)
			(effects
				(font
					(size 1.27 1.27)
					(thickness 0.15)
				)
				(justify left bottom)
				(hide yes)
			)
		)
		(property "Datasheet" "https://industrial.panasonic.com/cdbs/www-data/pdf/RDA0000/AOA0000C301.pdf"
			(at 58.42 43.18 0)
			(effects
				(font
					(size 1.27 1.27)
					(thickness 0.15)
				)
				(justify left bottom)
				(hide yes)
			)
		)
		(property "Description" ""
			(at 40.64 63.5 0)
			(effects
				(font
					(size 1.27 1.27)
				)
				(hide yes)
			)
		)
		(property "MPN" "ERJ2GE0R00X"
			(at 60.96 43.18 0)
			(effects
				(font
					(size 1.27 1.27)
					(thickness 0.15)
				)
				(justify left bottom)
				(hide yes)
			)
		)
		(property "Manufacturer" "Panasonic"
			(at 63.5 43.18 0)
			(effects
				(font
					(size 1.27 1.27)
					(thickness 0.15)
				)
				(justify left bottom)
				(hide yes)
			)
		)
		(property "License" "Apache-2.0"
			(at 66.04 43.18 0)
			(effects
				(font
					(size 1.27 1.27)
					(thickness 0.15)
				)
				(justify left bottom)
				(hide yes)
			)
		)
		(property "Author" "Antmicro"
			(at 68.58 43.18 0)
			(effects
				(font
					(size 1.27 1.27)
					(thickness 0.15)
				)
				(justify left bottom)
				(hide yes)
			)
		)
		(property "Val" "0R"
			(at 38.1 60.9599 90)
			(effects
				(font
					(size 1.27 1.27)
					(thickness 0.15)
				)
				(justify left)
			)
		)
		(property "Tolerance" "~"
			(at 50.8 43.18 0)
			(effects
				(font
					(size 1.27 1.27)
				)
				(justify left bottom)
				(hide yes)
			)
		)
		(property "Current" "1A"
			(at 71.12 43.18 0)
			(effects
				(font
					(size 1.27 1.27)
					(thickness 0.15)
				)
				(justify left bottom)
				(hide yes)
			)
		)
		(pin "1"
		)
		(pin "2"
		)
		(instances
			(project "cm4-baseboard"
				(path ""
					(reference "R205")
					(unit 1)
				)
			)
		)
	)
	(symbol
		(lib_id "antmicropower:GND")
		(at 358.14 245.11 0)
		(unit 1)
		(exclude_from_sim no)
		(in_bom yes)
		(on_board yes)
		(dnp no)
		(property "Reference" "#PWR0265"
			(at 367.03 247.65 0)
			(effects
				(font
					(size 1.27 1.27)
					(thickness 0.15)
				)
				(justify left bottom)
				(hide yes)
			)
		)
		(property "Value" "GND"
			(at 358.14 248.92 0)
			(effects
				(font
					(size 1.27 1.27)
					(thickness 0.15)
				)
			)
		)
		(property "Footprint" ""
			(at 367.03 252.73 0)
			(effects
				(font
					(size 1.27 1.27)
					(thickness 0.15)
				)
				(justify left bottom)
				(hide yes)
			)
		)
		(property "Datasheet" ""
			(at 367.03 257.81 0)
			(effects
				(font
					(size 1.27 1.27)
					(thickness 0.15)
				)
				(justify left bottom)
				(hide yes)
			)
		)
		(property "Description" ""
			(at 358.14 245.11 0)
			(effects
				(font
					(size 1.27 1.27)
				)
				(hide yes)
			)
		)
		(property "Author" "Antmicro"
			(at 367.03 252.73 0)
			(effects
				(font
					(size 1.27 1.27)
					(thickness 0.15)
				)
				(justify left bottom)
				(hide yes)
			)
		)
		(property "License" "Apache-2.0"
			(at 367.03 255.27 0)
			(effects
				(font
					(size 1.27 1.27)
					(thickness 0.15)
				)
				(justify left bottom)
				(hide yes)
			)
		)
		(pin "1"
		)
		(instances
			(project "cm4-baseboard"
				(path ""
					(reference "#PWR0265")
					(unit 1)
				)
			)
		)
	)
	(symbol
		(lib_id "antmicropower:GND")
		(at 176.53 223.52 0)
		(unit 1)
		(exclude_from_sim no)
		(in_bom yes)
		(on_board yes)
		(dnp no)
		(property "Reference" "#PWR0230"
			(at 185.42 226.06 0)
			(effects
				(font
					(size 1.27 1.27)
					(thickness 0.15)
				)
				(justify left bottom)
				(hide yes)
			)
		)
		(property "Value" "GND"
			(at 174.625 227.965 0)
			(effects
				(font
					(size 1.27 1.27)
					(thickness 0.15)
				)
				(justify left bottom)
			)
		)
		(property "Footprint" ""
			(at 185.42 231.14 0)
			(effects
				(font
					(size 1.27 1.27)
					(thickness 0.15)
				)
				(justify left bottom)
				(hide yes)
			)
		)
		(property "Datasheet" ""
			(at 185.42 236.22 0)
			(effects
				(font
					(size 1.27 1.27)
					(thickness 0.15)
				)
				(justify left bottom)
				(hide yes)
			)
		)
		(property "Description" ""
			(at 176.53 223.52 0)
			(effects
				(font
					(size 1.27 1.27)
				)
				(hide yes)
			)
		)
		(property "Author" "Antmicro"
			(at 185.42 231.14 0)
			(effects
				(font
					(size 1.27 1.27)
					(thickness 0.15)
				)
				(justify left bottom)
				(hide yes)
			)
		)
		(property "License" "Apache-2.0"
			(at 185.42 233.68 0)
			(effects
				(font
					(size 1.27 1.27)
					(thickness 0.15)
				)
				(justify left bottom)
				(hide yes)
			)
		)
		(pin "1"
		)
		(instances
			(project "cm4-baseboard"
				(path ""
					(reference "#PWR0230")
					(unit 1)
				)
			)
		)
	)
	(symbol
		(lib_id "antmicroResistors0402:R_10k_0402")
		(at 255.27 74.93 270)
		(mirror x)
		(unit 1)
		(exclude_from_sim no)
		(in_bom yes)
		(on_board yes)
		(dnp no)
		(property "Reference" "R237"
			(at 254 71.12 90)
			(effects
				(font
					(size 1.27 1.27)
					(thickness 0.15)
				)
				(justify right)
			)
		)
		(property "Value" "R_10k_0402"
			(at 242.57 54.61 0)
			(effects
				(font
					(size 1.27 1.27)
					(thickness 0.15)
				)
				(justify left bottom)
				(hide yes)
			)
		)
		(property "Footprint" "antmicro-footprints:R_0402_1005Metric"
			(at 240.03 54.61 0)
			(effects
				(font
					(size 1.27 1.27)
					(thickness 0.15)
				)
				(justify left bottom)
				(hide yes)
			)
		)
		(property "Datasheet" "https://www.bourns.com/docs/product-datasheets/cr.pdf"
			(at 237.49 54.61 0)
			(effects
				(font
					(size 1.27 1.27)
					(thickness 0.15)
				)
				(justify left bottom)
				(hide yes)
			)
		)
		(property "Description" ""
			(at 255.27 74.93 0)
			(effects
				(font
					(size 1.27 1.27)
				)
				(hide yes)
			)
		)
		(property "MPN" "CR0402-FX-1002GLF"
			(at 234.95 54.61 0)
			(effects
				(font
					(size 1.27 1.27)
					(thickness 0.15)
				)
				(justify left bottom)
				(hide yes)
			)
		)
		(property "Manufacturer" "Bourns"
			(at 232.41 54.61 0)
			(effects
				(font
					(size 1.27 1.27)
					(thickness 0.15)
				)
				(justify left bottom)
				(hide yes)
			)
		)
		(property "License" "Apache-2.0"
			(at 229.87 54.61 0)
			(effects
				(font
					(size 1.27 1.27)
					(thickness 0.15)
				)
				(justify left bottom)
				(hide yes)
			)
		)
		(property "Author" "Antmicro"
			(at 227.33 54.61 0)
			(effects
				(font
					(size 1.27 1.27)
					(thickness 0.15)
				)
				(justify left bottom)
				(hide yes)
			)
		)
		(property "Val" "10k"
			(at 254 73.66 90)
			(effects
				(font
					(size 1.27 1.27)
					(thickness 0.15)
				)
				(justify right)
			)
		)
		(property "Tolerance" "1%"
			(at 245.11 54.61 0)
			(effects
				(font
					(size 1.27 1.27)
				)
				(justify left bottom)
				(hide yes)
			)
		)
		(pin "1"
		)
		(pin "2"
		)
		(instances
			(project "cm4-baseboard"
				(path ""
					(reference "R237")
					(unit 1)
				)
			)
		)
	)
	(symbol
		(lib_id "antmicroLEDIndicationDiscrete:LED_G_0603_KP-1608CGCK")
		(at 306.07 27.94 270)
		(mirror x)
		(unit 1)
		(exclude_from_sim no)
		(in_bom no)
		(on_board yes)
		(dnp yes)
		(property "Reference" "D207"
			(at 312.42 24.13 90)
			(effects
				(font
					(size 1.27 1.27)
					(thickness 0.15)
				)
			)
		)
		(property "Value" "LED_G_0603_KP-1608CGCK"
			(at 298.45 5.08 0)
			(effects
				(font
					(size 1.27 1.27)
					(thickness 0.15)
				)
				(justify left bottom)
				(hide yes)
			)
		)
		(property "Footprint" "antmicro-footprints:LED_0603_1608Metric_G"
			(at 295.91 5.08 0)
			(effects
				(font
					(size 1.27 1.27)
					(thickness 0.15)
				)
				(justify left bottom)
				(hide yes)
			)
		)
		(property "Datasheet" "http://www.kingbright.com/attachments/file/psearch//000/00/00/KP-1608CGCK(Ver.23B).pdf"
			(at 293.37 5.08 0)
			(effects
				(font
					(size 1.27 1.27)
					(thickness 0.15)
				)
				(justify left bottom)
				(hide yes)
			)
		)
		(property "Description" ""
			(at 306.07 27.94 0)
			(effects
				(font
					(size 1.27 1.27)
				)
				(hide yes)
			)
		)
		(property "MPN" "KP-1608CGCK"
			(at 290.83 5.08 0)
			(effects
				(font
					(size 1.27 1.27)
					(thickness 0.15)
				)
				(justify left bottom)
				(hide yes)
			)
		)
		(property "Manufacturer" "Kingbright"
			(at 288.29 5.08 0)
			(effects
				(font
					(size 1.27 1.27)
					(thickness 0.15)
				)
				(justify left bottom)
				(hide yes)
			)
		)
		(property "Color" "Green"
			(at 312.42 26.67 90)
			(effects
				(font
					(size 1.27 1.27)
				)
			)
		)
		(property "Author" "Antmicro"
			(at 285.75 5.08 0)
			(effects
				(font
					(size 1.27 1.27)
					(thickness 0.15)
				)
				(justify left bottom)
				(hide yes)
			)
		)
		(property "License" "Apache-2.0"
			(at 283.21 5.08 0)
			(effects
				(font
					(size 1.27 1.27)
					(thickness 0.15)
				)
				(justify left bottom)
				(hide yes)
			)
		)
		(pin "2"
		)
		(pin "1"
		)
		(instances
			(project "cm4-baseboard"
				(path ""
					(reference "D207")
					(unit 1)
				)
			)
		)
	)
	(symbol
		(lib_id "antmicroResistors0402:R_0R_0402")
		(at 308.61 43.18 0)
		(mirror x)
		(unit 1)
		(exclude_from_sim no)
		(in_bom yes)
		(on_board yes)
		(dnp no)
		(property "Reference" "R240"
			(at 311.15 41.402 0)
			(effects
				(font
					(size 1.27 1.27)
				)
			)
		)
		(property "Value" "R_0R_0402"
			(at 308.61 39.37 0)
			(effects
				(font
					(size 1.27 1.27)
				)
				(justify left bottom)
				(hide yes)
			)
		)
		(property "Footprint" "antmicro-footprints:R_0402_1005Metric"
			(at 313.69 48.26 0)
			(effects
				(font
					(size 1.524 1.524)
				)
				(justify left bottom)
				(hide yes)
			)
		)
		(property "Datasheet" "https://industrial.panasonic.com/cdbs/www-data/pdf/RDA0000/AOA0000C301.pdf"
			(at 308.61 43.18 0)
			(effects
				(font
					(size 1.27 1.27)
				)
				(justify left bottom)
				(hide yes)
			)
		)
		(property "Description" ""
			(at 308.61 43.18 0)
			(effects
				(font
					(size 1.27 1.27)
				)
				(hide yes)
			)
		)
		(property "Manufacturer" "Panasonic"
			(at 313.69 53.34 0)
			(effects
				(font
					(size 1.524 1.524)
				)
				(justify left bottom)
				(hide yes)
			)
		)
		(property "MPN" "ERJ2GE0R00X"
			(at 313.69 50.8 0)
			(effects
				(font
					(size 1.524 1.524)
				)
				(justify left bottom)
				(hide yes)
			)
		)
		(property "Val" "0R"
			(at 311.15 43.18 0)
			(effects
				(font
					(size 1.27 1.27)
				)
			)
		)
		(property "License" "Apache-2.0"
			(at 328.93 17.78 0)
			(effects
				(font
					(size 1.27 1.27)
					(thickness 0.15)
				)
				(justify left bottom)
				(hide yes)
			)
		)
		(property "Author" "Antmicro"
			(at 328.93 15.24 0)
			(effects
				(font
					(size 1.27 1.27)
					(thickness 0.15)
				)
				(justify left bottom)
				(hide yes)
			)
		)
		(property "Tolerance" "~"
			(at 328.93 33.02 0)
			(effects
				(font
					(size 1.27 1.27)
				)
				(justify left bottom)
				(hide yes)
			)
		)
		(property "Current" "1A"
			(at 311.15 45.085 0)
			(effects
				(font
					(size 1.27 1.27)
					(thickness 0.15)
				)
				(hide yes)
			)
		)
		(pin "1"
		)
		(pin "2"
		)
		(instances
			(project "cm4-baseboard"
				(path ""
					(reference "R240")
					(unit 1)
				)
			)
		)
	)
	(symbol
		(lib_id "antmicroTestPoints:TP_0.75mm_SMD")
		(at 68.58 233.68 270)
		(unit 1)
		(exclude_from_sim no)
		(in_bom no)
		(on_board yes)
		(dnp no)
		(property "Reference" "TP217"
			(at 71.12 239.395 90)
			(effects
				(font
					(size 1.27 1.27)
				)
				(justify right)
			)
		)
		(property "Value" "TP_0.75mm_SMD"
			(at 66.04 233.68 0)
			(effects
				(font
					(size 1.27 1.27)
					(thickness 0.15)
				)
				(justify left bottom)
				(hide yes)
			)
		)
		(property "Footprint" "antmicro-footprints:TP_SMD_0.75mm"
			(at 73.66 238.76 0)
			(effects
				(font
					(size 1.27 1.27)
					(thickness 0.15)
				)
				(justify left bottom)
				(hide yes)
			)
		)
		(property "Datasheet" ""
			(at 76.2 238.76 0)
			(effects
				(font
					(size 1.27 1.27)
					(thickness 0.15)
				)
				(justify left bottom)
				(hide yes)
			)
		)
		(property "Description" ""
			(at 68.58 233.68 0)
			(effects
				(font
					(size 1.27 1.27)
				)
				(hide yes)
			)
		)
		(property "MPN" ""
			(at 68.58 233.68 0)
			(effects
				(font
					(size 1.27 1.27)
					(thickness 0.15)
				)
				(justify left bottom)
				(hide yes)
			)
		)
		(property "Manufacturer" ""
			(at 68.58 233.68 0)
			(effects
				(font
					(size 1.27 1.27)
					(thickness 0.15)
				)
				(justify left bottom)
				(hide yes)
			)
		)
		(property "Author" "Antmicro"
			(at 53.34 248.92 0)
			(effects
				(font
					(size 1.27 1.27)
					(thickness 0.15)
				)
				(justify left bottom)
				(hide yes)
			)
		)
		(property "License" "Apache-2.0"
			(at 50.8 248.92 0)
			(effects
				(font
					(size 1.27 1.27)
					(thickness 0.15)
				)
				(justify left bottom)
				(hide yes)
			)
		)
		(pin "1"
		)
		(instances
			(project "cm4-baseboard"
				(path ""
					(reference "TP217")
					(unit 1)
				)
			)
		)
	)
	(symbol
		(lib_id "antmicroTransistorsFETsMOSFETsSingle:PJE138K")
		(at 266.7 271.78 0)
		(mirror y)
		(unit 1)
		(exclude_from_sim no)
		(in_bom yes)
		(on_board yes)
		(dnp no)
		(property "Reference" "Q213"
			(at 255.27 267.9699 0)
			(effects
				(font
					(size 1.27 1.27)
				)
				(justify left)
			)
		)
		(property "Value" "PJE138K"
			(at 255.27 270.5099 0)
			(effects
				(font
					(size 1.27 1.27)
				)
				(justify left)
			)
		)
		(property "Footprint" "antmicro-footprints:SOT-523"
			(at 261.62 266.7 0)
			(effects
				(font
					(size 1.524 1.524)
				)
				(justify left bottom)
				(hide yes)
			)
		)
		(property "Datasheet" "https://www.mouser.com/datasheet/2/1057/PJE138K-1876698.pdf"
			(at 261.62 264.16 0)
			(effects
				(font
					(size 1.524 1.524)
				)
				(justify left bottom)
				(hide yes)
			)
		)
		(property "Description" ""
			(at 266.7 271.78 0)
			(effects
				(font
					(size 1.27 1.27)
				)
				(hide yes)
			)
		)
		(property "MPN" "PJE138K_R1_00001"
			(at 250.19 261.62 0)
			(effects
				(font
					(size 1.524 1.524)
				)
				(justify left bottom)
				(hide yes)
			)
		)
		(property "Manufacturer" "PANJIT"
			(at 261.62 261.62 0)
			(effects
				(font
					(size 1.524 1.524)
				)
				(justify left bottom)
				(hide yes)
			)
		)
		(property "Author" "Antmicro"
			(at 243.84 293.37 0)
			(effects
				(font
					(size 1.27 1.27)
					(thickness 0.15)
				)
				(justify left bottom)
				(hide yes)
			)
		)
		(property "License" "Apache-2.0"
			(at 243.84 295.91 0)
			(effects
				(font
					(size 1.27 1.27)
					(thickness 0.15)
				)
				(justify left bottom)
				(hide yes)
			)
		)
		(pin "1"
		)
		(pin "2"
		)
		(pin "3"
		)
		(instances
			(project "cm4-baseboard"
				(path ""
					(reference "Q213")
					(unit 1)
				)
			)
		)
	)
)
